FILE_TYPE = MACRO_DRAWING;
SET COLOR_WIRE YELLOW;
SET COLOR_PROP ORANGE;
SET COLOR_DOT WHITE;
SET COLOR_ARC YELLOW;
SET COLOR_BODY GREEN;
SET COLOR_NOTE PURPLE;
SET PROP_DISPLAY VALUE;
SET PAGE_NUMBER P46;
FORCEADD GENOA_SP5..10
(-4525 3525);
FORCEPROP 1 LAST LOCATION U26
J 0
(-5170 6356);
DISPLAY 0.489362 (-5170 6356);
PAINT SKYBLUE (-5170 6356);
FORCEPROP 0 LAST $SEC 10
J 0
(-5150 6400);
DISPLAY 0.680851 (-5150 6400);
PAINT MONO (-5150 6400);
DISPLAY INVISIBLE (-5150 6400);
FORCEPROP 0 LAST CDS_SEC 10
J 0
(-5175 6375);
DISPLAY 1.021277 (-5175 6375);
DISPLAY INVISIBLE (-5175 6375);
FORCEPROP 0 LASTPIN (-5325 2900) $PN BC16
J 2
(-5335 2910);
DISPLAY 0.489362 (-5335 2910);
PAINT MONO (-5335 2910);
FORCEPROP 0 LASTPIN (-5325 2850) $PN BD16
J 2
(-5335 2860);
DISPLAY 0.489362 (-5335 2860);
PAINT MONO (-5335 2860);
FORCEPROP 0 LASTPIN (-5325 1750) $PN BF16
J 2
(-5335 1760);
DISPLAY 0.489362 (-5335 1760);
PAINT MONO (-5335 1760);
FORCEPROP 0 LASTPIN (-5325 1700) $PN BG16
J 2
(-5335 1710);
DISPLAY 0.489362 (-5335 1710);
PAINT MONO (-5335 1710);
FORCEPROP 0 LASTPIN (-5325 2050) $PN AT18
J 2
(-5335 2060);
DISPLAY 0.489362 (-5335 2060);
PAINT MONO (-5335 2060);
FORCEPROP 0 LASTPIN (-5325 1950) $PN AU17
J 2
(-5335 1960);
DISPLAY 0.489362 (-5335 1960);
PAINT MONO (-5335 1960);
FORCEPROP 0 LASTPIN (-5325 2750) $PN AU16
J 2
(-5335 2760);
DISPLAY 0.489362 (-5335 2760);
PAINT MONO (-5335 2760);
FORCEPROP 0 LASTPIN (-5325 2700) $PN AV18
J 2
(-5335 2710);
DISPLAY 0.489362 (-5335 2710);
PAINT MONO (-5335 2710);
FORCEPROP 0 LASTPIN (-5325 2600) $PN BN17
J 2
(-5335 2610);
DISPLAY 0.489362 (-5335 2610);
PAINT MONO (-5335 2610);
FORCEPROP 0 LASTPIN (-5325 1600) $PN AV16
J 2
(-5335 1610);
DISPLAY 0.489362 (-5335 1610);
PAINT MONO (-5335 1610);
FORCEPROP 0 LASTPIN (-5325 1550) $PN AW17
J 2
(-5335 1560);
DISPLAY 0.489362 (-5335 1560);
PAINT MONO (-5335 1560);
FORCEPROP 0 LASTPIN (-5325 1450) $PN BP18
J 2
(-5335 1460);
DISPLAY 0.489362 (-5335 1460);
PAINT MONO (-5335 1460);
FORCEPROP 0 LASTPIN (-5325 3750) $PN AW16
J 2
(-5335 3760);
DISPLAY 0.489362 (-5335 3760);
PAINT MONO (-5335 3760);
FORCEPROP 0 LASTPIN (-5325 3700) $PN AY16
J 2
(-5335 3710);
DISPLAY 0.489362 (-5335 3710);
PAINT MONO (-5335 3710);
FORCEPROP 0 LASTPIN (-5325 3650) $PN AY18
J 2
(-5335 3660);
DISPLAY 0.489362 (-5335 3660);
PAINT MONO (-5335 3660);
FORCEPROP 0 LASTPIN (-5325 3600) $PN BA17
J 2
(-5335 3610);
DISPLAY 0.489362 (-5335 3610);
PAINT MONO (-5335 3610);
FORCEPROP 0 LASTPIN (-5325 3550) $PN BA16
J 2
(-5335 3560);
DISPLAY 0.489362 (-5335 3560);
PAINT MONO (-5335 3560);
FORCEPROP 0 LASTPIN (-5325 3500) $PN BB16
J 2
(-5335 3510);
DISPLAY 0.489362 (-5335 3510);
PAINT MONO (-5335 3510);
FORCEPROP 0 LASTPIN (-5325 3450) $PN BB18
J 2
(-5335 3460);
DISPLAY 0.489362 (-5335 3460);
PAINT MONO (-5335 3460);
FORCEPROP 0 LASTPIN (-3725 2300) $PN AJ16
J 0
(-3715 2310);
DISPLAY 0.489362 (-3715 2310);
PAINT MONO (-3715 2310);
FORCEPROP 0 LASTPIN (-3725 2250) $PN AK18
J 0
(-3715 2260);
DISPLAY 0.489362 (-3715 2260);
PAINT MONO (-3715 2260);
FORCEPROP 0 LASTPIN (-3725 2200) $PN AK16
J 0
(-3715 2210);
DISPLAY 0.489362 (-3715 2210);
PAINT MONO (-3715 2210);
FORCEPROP 0 LASTPIN (-3725 2150) $PN AL17
J 0
(-3715 2160);
DISPLAY 0.489362 (-3715 2160);
PAINT MONO (-3715 2160);
FORCEPROP 0 LASTPIN (-3725 2100) $PN AN16
J 0
(-3715 2110);
DISPLAY 0.489362 (-3715 2110);
PAINT MONO (-3715 2110);
FORCEPROP 0 LASTPIN (-3725 2050) $PN AP18
J 0
(-3715 2060);
DISPLAY 0.489362 (-3715 2060);
PAINT MONO (-3715 2060);
FORCEPROP 0 LASTPIN (-3725 2000) $PN AP16
J 0
(-3715 2010);
DISPLAY 0.489362 (-3715 2010);
PAINT MONO (-3715 2010);
FORCEPROP 0 LASTPIN (-3725 1950) $PN AR17
J 0
(-3715 1960);
DISPLAY 0.489362 (-3715 1960);
PAINT MONO (-3715 1960);
FORCEPROP 0 LASTPIN (-3725 5900) $PN E16
J 0
(-3715 5910);
DISPLAY 0.489362 (-3715 5910);
PAINT MONO (-3715 5910);
FORCEPROP 0 LASTPIN (-3725 5850) $PN F18
J 0
(-3715 5860);
DISPLAY 0.489362 (-3715 5860);
PAINT MONO (-3715 5860);
FORCEPROP 0 LASTPIN (-3725 5800) $PN F16
J 0
(-3715 5810);
DISPLAY 0.489362 (-3715 5810);
PAINT MONO (-3715 5810);
FORCEPROP 0 LASTPIN (-3725 5750) $PN G17
J 0
(-3715 5760);
DISPLAY 0.489362 (-3715 5760);
PAINT MONO (-3715 5760);
FORCEPROP 0 LASTPIN (-3725 5700) $PN J16
J 0
(-3715 5710);
DISPLAY 0.489362 (-3715 5710);
PAINT MONO (-3715 5710);
FORCEPROP 0 LASTPIN (-3725 5650) $PN K18
J 0
(-3715 5660);
DISPLAY 0.489362 (-3715 5660);
PAINT MONO (-3715 5660);
FORCEPROP 0 LASTPIN (-3725 5600) $PN K16
J 0
(-3715 5610);
DISPLAY 0.489362 (-3715 5610);
PAINT MONO (-3715 5610);
FORCEPROP 0 LASTPIN (-3725 5550) $PN L17
J 0
(-3715 5560);
DISPLAY 0.489362 (-3715 5560);
PAINT MONO (-3715 5560);
FORCEPROP 0 LASTPIN (-3725 5450) $PN L16
J 0
(-3715 5460);
DISPLAY 0.489362 (-3715 5460);
PAINT MONO (-3715 5460);
FORCEPROP 0 LASTPIN (-3725 5400) $PN M18
J 0
(-3715 5410);
DISPLAY 0.489362 (-3715 5410);
PAINT MONO (-3715 5410);
FORCEPROP 0 LASTPIN (-3725 5350) $PN M16
J 0
(-3715 5360);
DISPLAY 0.489362 (-3715 5360);
PAINT MONO (-3715 5360);
FORCEPROP 0 LASTPIN (-3725 5300) $PN N17
J 0
(-3715 5310);
DISPLAY 0.489362 (-3715 5310);
PAINT MONO (-3715 5310);
FORCEPROP 0 LASTPIN (-3725 5250) $PN R16
J 0
(-3715 5260);
DISPLAY 0.489362 (-3715 5260);
PAINT MONO (-3715 5260);
FORCEPROP 0 LASTPIN (-3725 5200) $PN T18
J 0
(-3715 5210);
DISPLAY 0.489362 (-3715 5210);
PAINT MONO (-3715 5210);
FORCEPROP 0 LASTPIN (-3725 5150) $PN T16
J 0
(-3715 5160);
DISPLAY 0.489362 (-3715 5160);
PAINT MONO (-3715 5160);
FORCEPROP 0 LASTPIN (-3725 5100) $PN U17
J 0
(-3715 5110);
DISPLAY 0.489362 (-3715 5110);
PAINT MONO (-3715 5110);
FORCEPROP 0 LASTPIN (-3725 5000) $PN U16
J 0
(-3715 5010);
DISPLAY 0.489362 (-3715 5010);
PAINT MONO (-3715 5010);
FORCEPROP 0 LASTPIN (-3725 4950) $PN V18
J 0
(-3715 4960);
DISPLAY 0.489362 (-3715 4960);
PAINT MONO (-3715 4960);
FORCEPROP 0 LASTPIN (-3725 4900) $PN V16
J 0
(-3715 4910);
DISPLAY 0.489362 (-3715 4910);
PAINT MONO (-3715 4910);
FORCEPROP 0 LASTPIN (-3725 4850) $PN W17
J 0
(-3715 4860);
DISPLAY 0.489362 (-3715 4860);
PAINT MONO (-3715 4860);
FORCEPROP 0 LASTPIN (-3725 4800) $PN AA16
J 0
(-3715 4810);
DISPLAY 0.489362 (-3715 4810);
PAINT MONO (-3715 4810);
FORCEPROP 0 LASTPIN (-3725 4750) $PN AB18
J 0
(-3715 4760);
DISPLAY 0.489362 (-3715 4760);
PAINT MONO (-3715 4760);
FORCEPROP 0 LASTPIN (-3725 4700) $PN AB16
J 0
(-3715 4710);
DISPLAY 0.489362 (-3715 4710);
PAINT MONO (-3715 4710);
FORCEPROP 0 LASTPIN (-3725 4650) $PN AC17
J 0
(-3715 4660);
DISPLAY 0.489362 (-3715 4660);
PAINT MONO (-3715 4660);
FORCEPROP 0 LASTPIN (-3725 4550) $PN AC16
J 0
(-3715 4560);
DISPLAY 0.489362 (-3715 4560);
PAINT MONO (-3715 4560);
FORCEPROP 0 LASTPIN (-3725 4500) $PN AD18
J 0
(-3715 4510);
DISPLAY 0.489362 (-3715 4510);
PAINT MONO (-3715 4510);
FORCEPROP 0 LASTPIN (-3725 4450) $PN AD16
J 0
(-3715 4460);
DISPLAY 0.489362 (-3715 4460);
PAINT MONO (-3715 4460);
FORCEPROP 0 LASTPIN (-3725 4400) $PN AE17
J 0
(-3715 4410);
DISPLAY 0.489362 (-3715 4410);
PAINT MONO (-3715 4410);
FORCEPROP 0 LASTPIN (-3725 4350) $PN AG16
J 0
(-3715 4360);
DISPLAY 0.489362 (-3715 4360);
PAINT MONO (-3715 4360);
FORCEPROP 0 LASTPIN (-3725 4300) $PN AH18
J 0
(-3715 4310);
DISPLAY 0.489362 (-3715 4310);
PAINT MONO (-3715 4310);
FORCEPROP 0 LASTPIN (-3725 4250) $PN AH16
J 0
(-3715 4260);
DISPLAY 0.489362 (-3715 4260);
PAINT MONO (-3715 4260);
FORCEPROP 0 LASTPIN (-3725 4200) $PN AJ17
J 0
(-3715 4210);
DISPLAY 0.489362 (-3715 4210);
PAINT MONO (-3715 4210);
FORCEPROP 0 LASTPIN (-5325 5900) $PN G16
J 2
(-5335 5910);
DISPLAY 0.489362 (-5335 5910);
PAINT MONO (-5335 5910);
FORCEPROP 0 LASTPIN (-5325 5800) $PN N16
J 2
(-5335 5810);
DISPLAY 0.489362 (-5335 5810);
PAINT MONO (-5335 5810);
FORCEPROP 0 LASTPIN (-5325 5700) $PN W16
J 2
(-5335 5710);
DISPLAY 0.489362 (-5335 5710);
PAINT MONO (-5335 5710);
FORCEPROP 0 LASTPIN (-5325 5600) $PN AE16
J 2
(-5335 5610);
DISPLAY 0.489362 (-5335 5610);
PAINT MONO (-5335 5610);
FORCEPROP 0 LASTPIN (-5325 5500) $PN AL16
J 2
(-5335 5510);
DISPLAY 0.489362 (-5335 5510);
PAINT MONO (-5335 5510);
FORCEPROP 0 LASTPIN (-5325 5400) $PN J17
J 2
(-5335 5410);
DISPLAY 0.489362 (-5335 5410);
PAINT MONO (-5335 5410);
FORCEPROP 0 LASTPIN (-5325 5300) $PN R17
J 2
(-5335 5310);
DISPLAY 0.489362 (-5335 5310);
PAINT MONO (-5335 5310);
FORCEPROP 0 LASTPIN (-5325 5200) $PN AA17
J 2
(-5335 5210);
DISPLAY 0.489362 (-5335 5210);
PAINT MONO (-5335 5210);
FORCEPROP 0 LASTPIN (-5325 5100) $PN AG17
J 2
(-5335 5110);
DISPLAY 0.489362 (-5335 5110);
PAINT MONO (-5335 5110);
FORCEPROP 0 LASTPIN (-5325 5000) $PN AN17
J 2
(-5335 5010);
DISPLAY 0.489362 (-5335 5010);
PAINT MONO (-5335 5010);
FORCEPROP 0 LASTPIN (-5325 5850) $PN H16
J 2
(-5335 5860);
DISPLAY 0.489362 (-5335 5860);
PAINT MONO (-5335 5860);
FORCEPROP 0 LASTPIN (-5325 5750) $PN P16
J 2
(-5335 5760);
DISPLAY 0.489362 (-5335 5760);
PAINT MONO (-5335 5760);
FORCEPROP 0 LASTPIN (-5325 5650) $PN Y16
J 2
(-5335 5660);
DISPLAY 0.489362 (-5335 5660);
PAINT MONO (-5335 5660);
FORCEPROP 0 LASTPIN (-5325 5550) $PN AF16
J 2
(-5335 5560);
DISPLAY 0.489362 (-5335 5560);
PAINT MONO (-5335 5560);
FORCEPROP 0 LASTPIN (-5325 5450) $PN AM16
J 2
(-5335 5460);
DISPLAY 0.489362 (-5335 5460);
PAINT MONO (-5335 5460);
FORCEPROP 0 LASTPIN (-5325 5350) $PN H18
J 2
(-5335 5360);
DISPLAY 0.489362 (-5335 5360);
PAINT MONO (-5335 5360);
FORCEPROP 0 LASTPIN (-5325 5250) $PN P18
J 2
(-5335 5260);
DISPLAY 0.489362 (-5335 5260);
PAINT MONO (-5335 5260);
FORCEPROP 0 LASTPIN (-5325 5150) $PN Y18
J 2
(-5335 5160);
DISPLAY 0.489362 (-5335 5160);
PAINT MONO (-5335 5160);
FORCEPROP 0 LASTPIN (-5325 5050) $PN AF18
J 2
(-5335 5060);
DISPLAY 0.489362 (-5335 5060);
PAINT MONO (-5335 5060);
FORCEPROP 0 LASTPIN (-5325 4950) $PN AM18
J 2
(-5335 4960);
DISPLAY 0.489362 (-5335 4960);
PAINT MONO (-5335 4960);
FORCEPROP 0 LASTPIN (-5325 2500) $PN BC17
J 2
(-5335 2510);
DISPLAY 0.489362 (-5335 2510);
PAINT MONO (-5335 2510);
FORCEPROP 0 LASTPIN (-5325 2400) $PN BM18
J 2
(-5335 2410);
DISPLAY 0.489362 (-5335 2410);
PAINT MONO (-5335 2410);
FORCEPROP 0 LASTPIN (-5325 2350) $PN BN16
J 2
(-5335 2360);
DISPLAY 0.489362 (-5335 2360);
PAINT MONO (-5335 2360);
FORCEPROP 0 LASTPIN (-5325 2250) $PN BP16
J 2
(-5335 2260);
DISPLAY 0.489362 (-5335 2260);
PAINT MONO (-5335 2260);
FORCEPROP 0 LASTPIN (-5325 1350) $PN BL16
J 2
(-5335 1360);
DISPLAY 0.489362 (-5335 1360);
PAINT MONO (-5335 1360);
FORCEPROP 0 LASTPIN (-5325 1300) $PN BM16
J 2
(-5335 1310);
DISPLAY 0.489362 (-5335 1310);
PAINT MONO (-5335 1310);
FORCEPROP 0 LASTPIN (-5325 1200) $PN BR16
J 2
(-5335 1210);
DISPLAY 0.489362 (-5335 1210);
PAINT MONO (-5335 1210);
FORCEPROP 0 LASTPIN (-5325 3350) $PN BG17
J 2
(-5335 3360);
DISPLAY 0.489362 (-5335 3360);
PAINT MONO (-5335 3360);
FORCEPROP 0 LASTPIN (-5325 3300) $PN BH18
J 2
(-5335 3310);
DISPLAY 0.489362 (-5335 3310);
PAINT MONO (-5335 3310);
FORCEPROP 0 LASTPIN (-5325 3250) $PN BH16
J 2
(-5335 3260);
DISPLAY 0.489362 (-5335 3260);
PAINT MONO (-5335 3260);
FORCEPROP 0 LASTPIN (-5325 3200) $PN BJ16
J 2
(-5335 3210);
DISPLAY 0.489362 (-5335 3210);
PAINT MONO (-5335 3210);
FORCEPROP 0 LASTPIN (-5325 3150) $PN BJ17
J 2
(-5335 3160);
DISPLAY 0.489362 (-5335 3160);
PAINT MONO (-5335 3160);
FORCEPROP 0 LASTPIN (-5325 3100) $PN BK18
J 2
(-5335 3110);
DISPLAY 0.489362 (-5335 3110);
PAINT MONO (-5335 3110);
FORCEPROP 0 LASTPIN (-5325 3050) $PN BK16
J 2
(-5335 3060);
DISPLAY 0.489362 (-5335 3060);
PAINT MONO (-5335 3060);
FORCEPROP 0 LASTPIN (-3725 1850) $PN BY16
J 0
(-3715 1860);
DISPLAY 0.489362 (-3715 1860);
PAINT MONO (-3715 1860);
FORCEPROP 0 LASTPIN (-3725 1800) $PN CA17
J 0
(-3715 1810);
DISPLAY 0.489362 (-3715 1810);
PAINT MONO (-3715 1810);
FORCEPROP 0 LASTPIN (-3725 1750) $PN CA16
J 0
(-3715 1760);
DISPLAY 0.489362 (-3715 1760);
PAINT MONO (-3715 1760);
FORCEPROP 0 LASTPIN (-3725 1700) $PN CB18
J 0
(-3715 1710);
DISPLAY 0.489362 (-3715 1710);
PAINT MONO (-3715 1710);
FORCEPROP 0 LASTPIN (-3725 1650) $PN BT16
J 0
(-3715 1660);
DISPLAY 0.489362 (-3715 1660);
PAINT MONO (-3715 1660);
FORCEPROP 0 LASTPIN (-3725 1600) $PN BU17
J 0
(-3715 1610);
DISPLAY 0.489362 (-3715 1610);
PAINT MONO (-3715 1610);
FORCEPROP 0 LASTPIN (-3725 1550) $PN BU16
J 0
(-3715 1560);
DISPLAY 0.489362 (-3715 1560);
PAINT MONO (-3715 1560);
FORCEPROP 0 LASTPIN (-3725 1500) $PN BV18
J 0
(-3715 1510);
DISPLAY 0.489362 (-3715 1510);
PAINT MONO (-3715 1510);
FORCEPROP 0 LASTPIN (-3725 4100) $PN CB16
J 0
(-3715 4110);
DISPLAY 0.489362 (-3715 4110);
PAINT MONO (-3715 4110);
FORCEPROP 0 LASTPIN (-3725 4050) $PN CC17
J 0
(-3715 4060);
DISPLAY 0.489362 (-3715 4060);
PAINT MONO (-3715 4060);
FORCEPROP 0 LASTPIN (-3725 4000) $PN CC16
J 0
(-3715 4010);
DISPLAY 0.489362 (-3715 4010);
PAINT MONO (-3715 4010);
FORCEPROP 0 LASTPIN (-3725 3950) $PN CD18
J 0
(-3715 3960);
DISPLAY 0.489362 (-3715 3960);
PAINT MONO (-3715 3960);
FORCEPROP 0 LASTPIN (-3725 3900) $PN CF16
J 0
(-3715 3910);
DISPLAY 0.489362 (-3715 3910);
PAINT MONO (-3715 3910);
FORCEPROP 0 LASTPIN (-3725 3850) $PN CG17
J 0
(-3715 3860);
DISPLAY 0.489362 (-3715 3860);
PAINT MONO (-3715 3860);
FORCEPROP 0 LASTPIN (-3725 3800) $PN CG16
J 0
(-3715 3810);
DISPLAY 0.489362 (-3715 3810);
PAINT MONO (-3715 3810);
FORCEPROP 0 LASTPIN (-3725 3750) $PN CH18
J 0
(-3715 3760);
DISPLAY 0.489362 (-3715 3760);
PAINT MONO (-3715 3760);
FORCEPROP 0 LASTPIN (-3725 3650) $PN CH16
J 0
(-3715 3660);
DISPLAY 0.489362 (-3715 3660);
PAINT MONO (-3715 3660);
FORCEPROP 0 LASTPIN (-3725 3600) $PN CJ17
J 0
(-3715 3610);
DISPLAY 0.489362 (-3715 3610);
PAINT MONO (-3715 3610);
FORCEPROP 0 LASTPIN (-3725 3550) $PN CJ16
J 0
(-3715 3560);
DISPLAY 0.489362 (-3715 3560);
PAINT MONO (-3715 3560);
FORCEPROP 0 LASTPIN (-3725 3500) $PN CK18
J 0
(-3715 3510);
DISPLAY 0.489362 (-3715 3510);
PAINT MONO (-3715 3510);
FORCEPROP 0 LASTPIN (-3725 3450) $PN CM16
J 0
(-3715 3460);
DISPLAY 0.489362 (-3715 3460);
PAINT MONO (-3715 3460);
FORCEPROP 0 LASTPIN (-3725 3400) $PN CN17
J 0
(-3715 3410);
DISPLAY 0.489362 (-3715 3410);
PAINT MONO (-3715 3410);
FORCEPROP 0 LASTPIN (-3725 3350) $PN CN16
J 0
(-3715 3360);
DISPLAY 0.489362 (-3715 3360);
PAINT MONO (-3715 3360);
FORCEPROP 0 LASTPIN (-3725 3300) $PN CP18
J 0
(-3715 3310);
DISPLAY 0.489362 (-3715 3310);
PAINT MONO (-3715 3310);
FORCEPROP 0 LASTPIN (-3725 3200) $PN CP16
J 0
(-3715 3210);
DISPLAY 0.489362 (-3715 3210);
PAINT MONO (-3715 3210);
FORCEPROP 0 LASTPIN (-3725 3150) $PN CR17
J 0
(-3715 3160);
DISPLAY 0.489362 (-3715 3160);
PAINT MONO (-3715 3160);
FORCEPROP 0 LASTPIN (-3725 3100) $PN CR16
J 0
(-3715 3110);
DISPLAY 0.489362 (-3715 3110);
PAINT MONO (-3715 3110);
FORCEPROP 0 LASTPIN (-3725 3050) $PN CT18
J 0
(-3715 3060);
DISPLAY 0.489362 (-3715 3060);
PAINT MONO (-3715 3060);
FORCEPROP 0 LASTPIN (-3725 3000) $PN CV16
J 0
(-3715 3010);
DISPLAY 0.489362 (-3715 3010);
PAINT MONO (-3715 3010);
FORCEPROP 0 LASTPIN (-3725 2950) $PN CW17
J 0
(-3715 2960);
DISPLAY 0.489362 (-3715 2960);
PAINT MONO (-3715 2960);
FORCEPROP 0 LASTPIN (-3725 2900) $PN CW16
J 0
(-3715 2910);
DISPLAY 0.489362 (-3715 2910);
PAINT MONO (-3715 2910);
FORCEPROP 0 LASTPIN (-3725 2850) $PN CY18
J 0
(-3715 2860);
DISPLAY 0.489362 (-3715 2860);
PAINT MONO (-3715 2860);
FORCEPROP 0 LASTPIN (-3725 2750) $PN CY16
J 0
(-3715 2760);
DISPLAY 0.489362 (-3715 2760);
PAINT MONO (-3715 2760);
FORCEPROP 0 LASTPIN (-3725 2700) $PN DA17
J 0
(-3715 2710);
DISPLAY 0.489362 (-3715 2710);
PAINT MONO (-3715 2710);
FORCEPROP 0 LASTPIN (-3725 2650) $PN DA16
J 0
(-3715 2660);
DISPLAY 0.489362 (-3715 2660);
PAINT MONO (-3715 2660);
FORCEPROP 0 LASTPIN (-3725 2600) $PN DB18
J 0
(-3715 2610);
DISPLAY 0.489362 (-3715 2610);
PAINT MONO (-3715 2610);
FORCEPROP 0 LASTPIN (-3725 2550) $PN DD16
J 0
(-3715 2560);
DISPLAY 0.489362 (-3715 2560);
PAINT MONO (-3715 2560);
FORCEPROP 0 LASTPIN (-3725 2500) $PN DE17
J 0
(-3715 2510);
DISPLAY 0.489362 (-3715 2510);
PAINT MONO (-3715 2510);
FORCEPROP 0 LASTPIN (-3725 2450) $PN DE16
J 0
(-3715 2460);
DISPLAY 0.489362 (-3715 2460);
PAINT MONO (-3715 2460);
FORCEPROP 0 LASTPIN (-3725 2400) $PN DF16
J 0
(-3715 2410);
DISPLAY 0.489362 (-3715 2410);
PAINT MONO (-3715 2410);
FORCEPROP 0 LASTPIN (-5325 4850) $PN CD16
J 2
(-5335 4860);
DISPLAY 0.489362 (-5335 4860);
PAINT MONO (-5335 4860);
FORCEPROP 0 LASTPIN (-5325 4750) $PN CK16
J 2
(-5335 4760);
DISPLAY 0.489362 (-5335 4760);
PAINT MONO (-5335 4760);
FORCEPROP 0 LASTPIN (-5325 4650) $PN CT16
J 2
(-5335 4660);
DISPLAY 0.489362 (-5335 4660);
PAINT MONO (-5335 4660);
FORCEPROP 0 LASTPIN (-5325 4550) $PN DB16
J 2
(-5335 4560);
DISPLAY 0.489362 (-5335 4560);
PAINT MONO (-5335 4560);
FORCEPROP 0 LASTPIN (-5325 4450) $PN BY18
J 2
(-5335 4460);
DISPLAY 0.489362 (-5335 4460);
PAINT MONO (-5335 4460);
FORCEPROP 0 LASTPIN (-5325 4350) $PN CF18
J 2
(-5335 4360);
DISPLAY 0.489362 (-5335 4360);
PAINT MONO (-5335 4360);
FORCEPROP 0 LASTPIN (-5325 4250) $PN CM18
J 2
(-5335 4260);
DISPLAY 0.489362 (-5335 4260);
PAINT MONO (-5335 4260);
FORCEPROP 0 LASTPIN (-5325 4150) $PN CV18
J 2
(-5335 4160);
DISPLAY 0.489362 (-5335 4160);
PAINT MONO (-5335 4160);
FORCEPROP 0 LASTPIN (-5325 4050) $PN DD18
J 2
(-5335 4060);
DISPLAY 0.489362 (-5335 4060);
PAINT MONO (-5335 4060);
FORCEPROP 0 LASTPIN (-5325 3950) $PN BV16
J 2
(-5335 3960);
DISPLAY 0.489362 (-5335 3960);
PAINT MONO (-5335 3960);
FORCEPROP 0 LASTPIN (-5325 4800) $PN CE16
J 2
(-5335 4810);
DISPLAY 0.489362 (-5335 4810);
PAINT MONO (-5335 4810);
FORCEPROP 0 LASTPIN (-5325 4700) $PN CL16
J 2
(-5335 4710);
DISPLAY 0.489362 (-5335 4710);
PAINT MONO (-5335 4710);
FORCEPROP 0 LASTPIN (-5325 4600) $PN CU16
J 2
(-5335 4610);
DISPLAY 0.489362 (-5335 4610);
PAINT MONO (-5335 4610);
FORCEPROP 0 LASTPIN (-5325 4500) $PN DC16
J 2
(-5335 4510);
DISPLAY 0.489362 (-5335 4510);
PAINT MONO (-5335 4510);
FORCEPROP 0 LASTPIN (-5325 4400) $PN BW17
J 2
(-5335 4410);
DISPLAY 0.489362 (-5335 4410);
PAINT MONO (-5335 4410);
FORCEPROP 0 LASTPIN (-5325 4300) $PN CE17
J 2
(-5335 4310);
DISPLAY 0.489362 (-5335 4310);
PAINT MONO (-5335 4310);
FORCEPROP 0 LASTPIN (-5325 4200) $PN CL17
J 2
(-5335 4210);
DISPLAY 0.489362 (-5335 4210);
PAINT MONO (-5335 4210);
FORCEPROP 0 LASTPIN (-5325 4100) $PN CU17
J 2
(-5335 4110);
DISPLAY 0.489362 (-5335 4110);
PAINT MONO (-5335 4110);
FORCEPROP 0 LASTPIN (-5325 4000) $PN DC17
J 2
(-5335 4010);
DISPLAY 0.489362 (-5335 4010);
PAINT MONO (-5335 4010);
FORCEPROP 0 LASTPIN (-5325 3900) $PN BW16
J 2
(-5335 3910);
DISPLAY 0.489362 (-5335 3910);
PAINT MONO (-5335 3910);
FORCEPROP 0 LASTPIN (-5325 2150) $PN BL17
J 2
(-5335 2160);
DISPLAY 0.489362 (-5335 2160);
PAINT MONO (-5335 2160);
FORCEPROP 0 LASTPIN (-5325 1100) $PN BF18
J 2
(-5335 1110);
DISPLAY 0.489362 (-5335 1110);
PAINT MONO (-5335 1110);
FORCEPROP 2 LAST PART_TYPE SMLF
J 0
(-5175 6305);
DISPLAY 1.021277 (-5175 6305);
FORCEPROP 1 LAST MATERIAL IO
J 0
(-5170 6082);
DISPLAY 0.489362 (-5170 6082);
PAINT SKYBLUE (-5170 6082);
FORCEPROP 2 LAST VALUE SOCKET6096_13568-001
J 0
(-5175 6205);
DISPLAY 0.489362 (-5175 6205);
PAINT SKYBLUE (-5175 6205);
FORCEPROP 2 LAST CDS_LIB pure_quanta
J 0
(-4525 3525);
DISPLAY INVISIBLE (-4525 3525);
FORCEPROP 1 LAST CDS_LMAN_SYM_OUTLINE -650,2525,650,-2525
J 0
(-4525 3525);
DISPLAY 0.468085 (-4525 3525);
PAINT GREEN (-4525 3525);
DISPLAY INVISIBLE (-4525 3525);
FORCEPROP 1 LAST NEEDS_NO_SIZE TRUE
J 0
(-4525 3525);
DISPLAY 0.723404 (-4525 3525);
PAINT GREEN (-4525 3525);
DISPLAY INVISIBLE (-4525 3525);
FORCEPROP 1 LAST PATH I159
J 0
(-4525 3525);
DISPLAY 0.723404 (-4525 3525);
PAINT GREEN (-4525 3525);
DISPLAY INVISIBLE (-4525 3525);
FORCEPROP 1 LAST PART_NUMBER DGA^6000030
J 0
(-5170 6209);
DISPLAY 0.489362 (-5170 6209);
PAINT SKYBLUE (-5170 6209);
DISPLAY INVISIBLE (-5170 6209);
FORCEADD OFFPAGE..3
(-2525 5925);
FORCEPROP 2 LAST $XR0 107 
J 0
(-2311 5925);
DISPLAY 0.638298 (-2311 5925);
PAINT MONO (-2311 5925);
FORCEPROP 2 LAST CDS_LIB mstr_standard
J 0
(-2525 5925);
DISPLAY 0.723404 (-2525 5925);
PAINT MONO (-2525 5925);
DISPLAY INVISIBLE (-2525 5925);
FORCEPROP 1 LAST OFFPAGE TRUE
J 0
(-2200 5800);
DISPLAY 0.872340 (-2200 5800);
PAINT GREEN (-2200 5800);
DISPLAY INVISIBLE (-2200 5800);
FORCEPROP 1 LAST COMMENT_BODY TRUE
J 0
(-2575 5825);
DISPLAY 0.872340 (-2575 5825);
PAINT GREEN (-2575 5825);
DISPLAY INVISIBLE (-2575 5825);
FORCEPROP 2 LAST PATH I160
J 0
(-2300 5975);
DISPLAY 1.021277 (-2300 5975);
DISPLAY INVISIBLE (-2300 5975);
FORCEADD TAP..1
(-3250 5900);
FORCEPROP 3 LASTPIN (-3300 5900) SIG_NAME M_J_CPU1_SA_DQ<0>
J 0
(-3290 5910);
DISPLAY 0.659574 (-3290 5910);
PAINT MONO (-3290 5910);
DISPLAY INVISIBLE (-3290 5910);
FORCEPROP 1 LASTPIN (-3300 5900) BN 0
J 0
(-3312 5908);
DISPLAY 0.489362 (-3312 5908);
PAINT GREEN (-3312 5908);
FORCEPROP 2 LAST CDS_LIB mstr_standard
J 0
(-3250 5900);
DISPLAY 0.723404 (-3250 5900);
PAINT MONO (-3250 5900);
DISPLAY INVISIBLE (-3250 5900);
FORCEPROP 1 LAST BODY_TYPE PLUMBING
J 0
(-3250 5950);
DISPLAY 0.872340 (-3250 5950);
PAINT GREEN (-3250 5950);
DISPLAY INVISIBLE (-3250 5950);
FORCEPROP 1 LAST HDL_TAP TRUE
J 0
(-2925 5775);
DISPLAY 0.872340 (-2925 5775);
DISPLAY INVISIBLE (-2925 5775);
FORCEPROP 1 LAST PATH I161
J 0
(-3252 5900);
DISPLAY 0.872340 (-3252 5900);
PAINT GREEN (-3252 5900);
DISPLAY INVISIBLE (-3252 5900);
FORCEADD TAP..1
(-3250 5850);
FORCEPROP 3 LASTPIN (-3300 5850) SIG_NAME M_J_CPU1_SA_DQ<1>
J 0
(-3290 5860);
DISPLAY 0.659574 (-3290 5860);
PAINT MONO (-3290 5860);
DISPLAY INVISIBLE (-3290 5860);
FORCEPROP 1 LASTPIN (-3300 5850) BN 1
J 0
(-3312 5858);
DISPLAY 0.489362 (-3312 5858);
PAINT GREEN (-3312 5858);
FORCEPROP 2 LAST CDS_LIB mstr_standard
J 0
(-3250 5850);
DISPLAY 0.723404 (-3250 5850);
PAINT MONO (-3250 5850);
DISPLAY INVISIBLE (-3250 5850);
FORCEPROP 1 LAST BODY_TYPE PLUMBING
J 0
(-3250 5900);
DISPLAY 0.872340 (-3250 5900);
PAINT GREEN (-3250 5900);
DISPLAY INVISIBLE (-3250 5900);
FORCEPROP 1 LAST HDL_TAP TRUE
J 0
(-2925 5725);
DISPLAY 0.872340 (-2925 5725);
DISPLAY INVISIBLE (-2925 5725);
FORCEPROP 1 LAST PATH I162
J 0
(-3252 5850);
DISPLAY 0.872340 (-3252 5850);
PAINT GREEN (-3252 5850);
DISPLAY INVISIBLE (-3252 5850);
FORCEADD TAP..1
(-3250 5800);
FORCEPROP 3 LASTPIN (-3300 5800) SIG_NAME M_J_CPU1_SA_DQ<2>
J 0
(-3290 5810);
DISPLAY 0.659574 (-3290 5810);
PAINT MONO (-3290 5810);
DISPLAY INVISIBLE (-3290 5810);
FORCEPROP 1 LASTPIN (-3300 5800) BN 2
J 0
(-3312 5808);
DISPLAY 0.489362 (-3312 5808);
PAINT GREEN (-3312 5808);
FORCEPROP 2 LAST CDS_LIB mstr_standard
J 0
(-3250 5800);
DISPLAY 0.723404 (-3250 5800);
PAINT MONO (-3250 5800);
DISPLAY INVISIBLE (-3250 5800);
FORCEPROP 1 LAST BODY_TYPE PLUMBING
J 0
(-3250 5850);
DISPLAY 0.872340 (-3250 5850);
PAINT GREEN (-3250 5850);
DISPLAY INVISIBLE (-3250 5850);
FORCEPROP 1 LAST HDL_TAP TRUE
J 0
(-2925 5675);
DISPLAY 0.872340 (-2925 5675);
DISPLAY INVISIBLE (-2925 5675);
FORCEPROP 1 LAST PATH I163
J 0
(-3252 5800);
DISPLAY 0.872340 (-3252 5800);
PAINT GREEN (-3252 5800);
DISPLAY INVISIBLE (-3252 5800);
FORCEADD TAP..1
(-3250 5700);
FORCEPROP 3 LASTPIN (-3300 5700) SIG_NAME M_J_CPU1_SA_DQ<4>
J 0
(-3290 5710);
DISPLAY 0.659574 (-3290 5710);
PAINT MONO (-3290 5710);
DISPLAY INVISIBLE (-3290 5710);
FORCEPROP 1 LASTPIN (-3300 5700) BN 4
J 0
(-3312 5708);
DISPLAY 0.489362 (-3312 5708);
PAINT GREEN (-3312 5708);
FORCEPROP 2 LAST CDS_LIB mstr_standard
J 0
(-3250 5700);
DISPLAY 0.723404 (-3250 5700);
PAINT MONO (-3250 5700);
DISPLAY INVISIBLE (-3250 5700);
FORCEPROP 1 LAST BODY_TYPE PLUMBING
J 0
(-3250 5750);
DISPLAY 0.872340 (-3250 5750);
PAINT GREEN (-3250 5750);
DISPLAY INVISIBLE (-3250 5750);
FORCEPROP 1 LAST HDL_TAP TRUE
J 0
(-2925 5575);
DISPLAY 0.872340 (-2925 5575);
DISPLAY INVISIBLE (-2925 5575);
FORCEPROP 1 LAST PATH I164
J 0
(-3252 5700);
DISPLAY 0.872340 (-3252 5700);
PAINT GREEN (-3252 5700);
DISPLAY INVISIBLE (-3252 5700);
FORCEADD TAP..1
(-3250 5750);
FORCEPROP 3 LASTPIN (-3300 5750) SIG_NAME M_J_CPU1_SA_DQ<3>
J 0
(-3290 5760);
DISPLAY 0.659574 (-3290 5760);
PAINT MONO (-3290 5760);
DISPLAY INVISIBLE (-3290 5760);
FORCEPROP 1 LASTPIN (-3300 5750) BN 3
J 0
(-3312 5758);
DISPLAY 0.489362 (-3312 5758);
PAINT GREEN (-3312 5758);
FORCEPROP 2 LAST CDS_LIB mstr_standard
J 0
(-3250 5750);
DISPLAY 0.723404 (-3250 5750);
PAINT MONO (-3250 5750);
DISPLAY INVISIBLE (-3250 5750);
FORCEPROP 1 LAST BODY_TYPE PLUMBING
J 0
(-3250 5800);
DISPLAY 0.872340 (-3250 5800);
PAINT GREEN (-3250 5800);
DISPLAY INVISIBLE (-3250 5800);
FORCEPROP 1 LAST HDL_TAP TRUE
J 0
(-2925 5625);
DISPLAY 0.872340 (-2925 5625);
DISPLAY INVISIBLE (-2925 5625);
FORCEPROP 1 LAST PATH I165
J 0
(-3252 5750);
DISPLAY 0.872340 (-3252 5750);
PAINT GREEN (-3252 5750);
DISPLAY INVISIBLE (-3252 5750);
FORCEADD TAP..1
(-3250 5650);
FORCEPROP 3 LASTPIN (-3300 5650) SIG_NAME M_J_CPU1_SA_DQ<5>
J 0
(-3290 5660);
DISPLAY 0.659574 (-3290 5660);
PAINT MONO (-3290 5660);
DISPLAY INVISIBLE (-3290 5660);
FORCEPROP 1 LASTPIN (-3300 5650) BN 5
J 0
(-3312 5658);
DISPLAY 0.489362 (-3312 5658);
PAINT GREEN (-3312 5658);
FORCEPROP 2 LAST CDS_LIB mstr_standard
J 0
(-3250 5650);
DISPLAY 0.723404 (-3250 5650);
PAINT MONO (-3250 5650);
DISPLAY INVISIBLE (-3250 5650);
FORCEPROP 1 LAST BODY_TYPE PLUMBING
J 0
(-3250 5700);
DISPLAY 0.872340 (-3250 5700);
PAINT GREEN (-3250 5700);
DISPLAY INVISIBLE (-3250 5700);
FORCEPROP 1 LAST HDL_TAP TRUE
J 0
(-2925 5525);
DISPLAY 0.872340 (-2925 5525);
DISPLAY INVISIBLE (-2925 5525);
FORCEPROP 1 LAST PATH I166
J 0
(-3252 5650);
DISPLAY 0.872340 (-3252 5650);
PAINT GREEN (-3252 5650);
DISPLAY INVISIBLE (-3252 5650);
FORCEADD TAP..1
(-3250 5600);
FORCEPROP 3 LASTPIN (-3300 5600) SIG_NAME M_J_CPU1_SA_DQ<6>
J 0
(-3290 5610);
DISPLAY 0.659574 (-3290 5610);
PAINT MONO (-3290 5610);
DISPLAY INVISIBLE (-3290 5610);
FORCEPROP 1 LASTPIN (-3300 5600) BN 6
J 0
(-3312 5608);
DISPLAY 0.489362 (-3312 5608);
PAINT GREEN (-3312 5608);
FORCEPROP 2 LAST CDS_LIB mstr_standard
J 0
(-3250 5600);
DISPLAY 0.723404 (-3250 5600);
PAINT MONO (-3250 5600);
DISPLAY INVISIBLE (-3250 5600);
FORCEPROP 1 LAST BODY_TYPE PLUMBING
J 0
(-3250 5650);
DISPLAY 0.872340 (-3250 5650);
PAINT GREEN (-3250 5650);
DISPLAY INVISIBLE (-3250 5650);
FORCEPROP 1 LAST HDL_TAP TRUE
J 0
(-2925 5475);
DISPLAY 0.872340 (-2925 5475);
DISPLAY INVISIBLE (-2925 5475);
FORCEPROP 1 LAST PATH I167
J 0
(-3252 5600);
DISPLAY 0.872340 (-3252 5600);
PAINT GREEN (-3252 5600);
DISPLAY INVISIBLE (-3252 5600);
FORCEADD TAP..1
(-3250 5550);
FORCEPROP 3 LASTPIN (-3300 5550) SIG_NAME M_J_CPU1_SA_DQ<7>
J 0
(-3290 5560);
DISPLAY 0.659574 (-3290 5560);
PAINT MONO (-3290 5560);
DISPLAY INVISIBLE (-3290 5560);
FORCEPROP 1 LASTPIN (-3300 5550) BN 7
J 0
(-3312 5558);
DISPLAY 0.489362 (-3312 5558);
PAINT GREEN (-3312 5558);
FORCEPROP 2 LAST CDS_LIB mstr_standard
J 0
(-3250 5550);
DISPLAY 0.723404 (-3250 5550);
PAINT MONO (-3250 5550);
DISPLAY INVISIBLE (-3250 5550);
FORCEPROP 1 LAST BODY_TYPE PLUMBING
J 0
(-3250 5600);
DISPLAY 0.872340 (-3250 5600);
PAINT GREEN (-3250 5600);
DISPLAY INVISIBLE (-3250 5600);
FORCEPROP 1 LAST HDL_TAP TRUE
J 0
(-2925 5425);
DISPLAY 0.872340 (-2925 5425);
DISPLAY INVISIBLE (-2925 5425);
FORCEPROP 1 LAST PATH I168
J 0
(-3252 5550);
DISPLAY 0.872340 (-3252 5550);
PAINT GREEN (-3252 5550);
DISPLAY INVISIBLE (-3252 5550);
FORCEADD TAP..1
(-3250 5400);
FORCEPROP 3 LASTPIN (-3300 5400) SIG_NAME M_J_CPU1_SA_DQ<9>
J 0
(-3290 5410);
DISPLAY 0.659574 (-3290 5410);
PAINT MONO (-3290 5410);
DISPLAY INVISIBLE (-3290 5410);
FORCEPROP 1 LASTPIN (-3300 5400) BN 9
J 0
(-3312 5408);
DISPLAY 0.489362 (-3312 5408);
PAINT GREEN (-3312 5408);
FORCEPROP 2 LAST CDS_LIB mstr_standard
J 0
(-3250 5400);
DISPLAY 0.723404 (-3250 5400);
PAINT MONO (-3250 5400);
DISPLAY INVISIBLE (-3250 5400);
FORCEPROP 1 LAST BODY_TYPE PLUMBING
J 0
(-3250 5450);
DISPLAY 0.872340 (-3250 5450);
PAINT GREEN (-3250 5450);
DISPLAY INVISIBLE (-3250 5450);
FORCEPROP 1 LAST HDL_TAP TRUE
J 0
(-2925 5275);
DISPLAY 0.872340 (-2925 5275);
DISPLAY INVISIBLE (-2925 5275);
FORCEPROP 1 LAST PATH I169
J 0
(-3252 5400);
DISPLAY 0.872340 (-3252 5400);
PAINT GREEN (-3252 5400);
DISPLAY INVISIBLE (-3252 5400);
FORCEADD TAP..1
(-3250 5450);
FORCEPROP 3 LASTPIN (-3300 5450) SIG_NAME M_J_CPU1_SA_DQ<8>
J 0
(-3290 5460);
DISPLAY 0.659574 (-3290 5460);
PAINT MONO (-3290 5460);
DISPLAY INVISIBLE (-3290 5460);
FORCEPROP 1 LASTPIN (-3300 5450) BN 8
J 0
(-3312 5458);
DISPLAY 0.489362 (-3312 5458);
PAINT GREEN (-3312 5458);
FORCEPROP 2 LAST CDS_LIB mstr_standard
J 0
(-3250 5450);
DISPLAY 0.723404 (-3250 5450);
PAINT MONO (-3250 5450);
DISPLAY INVISIBLE (-3250 5450);
FORCEPROP 1 LAST BODY_TYPE PLUMBING
J 0
(-3250 5500);
DISPLAY 0.872340 (-3250 5500);
PAINT GREEN (-3250 5500);
DISPLAY INVISIBLE (-3250 5500);
FORCEPROP 1 LAST HDL_TAP TRUE
J 0
(-2925 5325);
DISPLAY 0.872340 (-2925 5325);
DISPLAY INVISIBLE (-2925 5325);
FORCEPROP 1 LAST PATH I170
J 0
(-3252 5450);
DISPLAY 0.872340 (-3252 5450);
PAINT GREEN (-3252 5450);
DISPLAY INVISIBLE (-3252 5450);
FORCEADD TAP..1
(-3250 5350);
FORCEPROP 3 LASTPIN (-3300 5350) SIG_NAME M_J_CPU1_SA_DQ<10>
J 0
(-3290 5360);
DISPLAY 0.659574 (-3290 5360);
PAINT MONO (-3290 5360);
DISPLAY INVISIBLE (-3290 5360);
FORCEPROP 1 LASTPIN (-3300 5350) BN 10
J 0
(-3312 5358);
DISPLAY 0.489362 (-3312 5358);
PAINT GREEN (-3312 5358);
FORCEPROP 2 LAST CDS_LIB mstr_standard
J 0
(-3250 5350);
DISPLAY 0.723404 (-3250 5350);
PAINT MONO (-3250 5350);
DISPLAY INVISIBLE (-3250 5350);
FORCEPROP 1 LAST BODY_TYPE PLUMBING
J 0
(-3250 5400);
DISPLAY 0.872340 (-3250 5400);
PAINT GREEN (-3250 5400);
DISPLAY INVISIBLE (-3250 5400);
FORCEPROP 1 LAST HDL_TAP TRUE
J 0
(-2925 5225);
DISPLAY 0.872340 (-2925 5225);
DISPLAY INVISIBLE (-2925 5225);
FORCEPROP 1 LAST PATH I171
J 0
(-3252 5350);
DISPLAY 0.872340 (-3252 5350);
PAINT GREEN (-3252 5350);
DISPLAY INVISIBLE (-3252 5350);
FORCEADD TAP..1
(-3250 5300);
FORCEPROP 3 LASTPIN (-3300 5300) SIG_NAME M_J_CPU1_SA_DQ<11>
J 0
(-3290 5310);
DISPLAY 0.659574 (-3290 5310);
PAINT MONO (-3290 5310);
DISPLAY INVISIBLE (-3290 5310);
FORCEPROP 1 LASTPIN (-3300 5300) BN 11
J 0
(-3312 5308);
DISPLAY 0.489362 (-3312 5308);
PAINT GREEN (-3312 5308);
FORCEPROP 2 LAST CDS_LIB mstr_standard
J 0
(-3250 5300);
DISPLAY 0.723404 (-3250 5300);
PAINT MONO (-3250 5300);
DISPLAY INVISIBLE (-3250 5300);
FORCEPROP 1 LAST BODY_TYPE PLUMBING
J 0
(-3250 5350);
DISPLAY 0.872340 (-3250 5350);
PAINT GREEN (-3250 5350);
DISPLAY INVISIBLE (-3250 5350);
FORCEPROP 1 LAST HDL_TAP TRUE
J 0
(-2925 5175);
DISPLAY 0.872340 (-2925 5175);
DISPLAY INVISIBLE (-2925 5175);
FORCEPROP 1 LAST PATH I172
J 0
(-3252 5300);
DISPLAY 0.872340 (-3252 5300);
PAINT GREEN (-3252 5300);
DISPLAY INVISIBLE (-3252 5300);
FORCEADD TAP..1
(-3250 5250);
FORCEPROP 3 LASTPIN (-3300 5250) SIG_NAME M_J_CPU1_SA_DQ<12>
J 0
(-3290 5260);
DISPLAY 0.659574 (-3290 5260);
PAINT MONO (-3290 5260);
DISPLAY INVISIBLE (-3290 5260);
FORCEPROP 1 LASTPIN (-3300 5250) BN 12
J 0
(-3312 5258);
DISPLAY 0.489362 (-3312 5258);
PAINT GREEN (-3312 5258);
FORCEPROP 2 LAST CDS_LIB mstr_standard
J 0
(-3250 5250);
DISPLAY 0.723404 (-3250 5250);
PAINT MONO (-3250 5250);
DISPLAY INVISIBLE (-3250 5250);
FORCEPROP 1 LAST BODY_TYPE PLUMBING
J 0
(-3250 5300);
DISPLAY 0.872340 (-3250 5300);
PAINT GREEN (-3250 5300);
DISPLAY INVISIBLE (-3250 5300);
FORCEPROP 1 LAST HDL_TAP TRUE
J 0
(-2925 5125);
DISPLAY 0.872340 (-2925 5125);
DISPLAY INVISIBLE (-2925 5125);
FORCEPROP 1 LAST PATH I173
J 0
(-3252 5250);
DISPLAY 0.872340 (-3252 5250);
PAINT GREEN (-3252 5250);
DISPLAY INVISIBLE (-3252 5250);
FORCEADD TAP..1
(-3250 5200);
FORCEPROP 3 LASTPIN (-3300 5200) SIG_NAME M_J_CPU1_SA_DQ<13>
J 0
(-3290 5210);
DISPLAY 0.659574 (-3290 5210);
PAINT MONO (-3290 5210);
DISPLAY INVISIBLE (-3290 5210);
FORCEPROP 1 LASTPIN (-3300 5200) BN 13
J 0
(-3312 5208);
DISPLAY 0.489362 (-3312 5208);
PAINT GREEN (-3312 5208);
FORCEPROP 2 LAST CDS_LIB mstr_standard
J 0
(-3250 5200);
DISPLAY 0.723404 (-3250 5200);
PAINT MONO (-3250 5200);
DISPLAY INVISIBLE (-3250 5200);
FORCEPROP 1 LAST BODY_TYPE PLUMBING
J 0
(-3250 5250);
DISPLAY 0.872340 (-3250 5250);
PAINT GREEN (-3250 5250);
DISPLAY INVISIBLE (-3250 5250);
FORCEPROP 1 LAST HDL_TAP TRUE
J 0
(-2925 5075);
DISPLAY 0.872340 (-2925 5075);
DISPLAY INVISIBLE (-2925 5075);
FORCEPROP 1 LAST PATH I174
J 0
(-3252 5200);
DISPLAY 0.872340 (-3252 5200);
PAINT GREEN (-3252 5200);
DISPLAY INVISIBLE (-3252 5200);
FORCEADD TAP..1
(-3250 5150);
FORCEPROP 3 LASTPIN (-3300 5150) SIG_NAME M_J_CPU1_SA_DQ<14>
J 0
(-3290 5160);
DISPLAY 0.659574 (-3290 5160);
PAINT MONO (-3290 5160);
DISPLAY INVISIBLE (-3290 5160);
FORCEPROP 1 LASTPIN (-3300 5150) BN 14
J 0
(-3312 5158);
DISPLAY 0.489362 (-3312 5158);
PAINT GREEN (-3312 5158);
FORCEPROP 2 LAST CDS_LIB mstr_standard
J 0
(-3250 5150);
DISPLAY 0.723404 (-3250 5150);
PAINT MONO (-3250 5150);
DISPLAY INVISIBLE (-3250 5150);
FORCEPROP 1 LAST BODY_TYPE PLUMBING
J 0
(-3250 5200);
DISPLAY 0.872340 (-3250 5200);
PAINT GREEN (-3250 5200);
DISPLAY INVISIBLE (-3250 5200);
FORCEPROP 1 LAST HDL_TAP TRUE
J 0
(-2925 5025);
DISPLAY 0.872340 (-2925 5025);
DISPLAY INVISIBLE (-2925 5025);
FORCEPROP 1 LAST PATH I175
J 0
(-3252 5150);
DISPLAY 0.872340 (-3252 5150);
PAINT GREEN (-3252 5150);
DISPLAY INVISIBLE (-3252 5150);
FORCEADD TAP..1
(-3250 5100);
FORCEPROP 3 LASTPIN (-3300 5100) SIG_NAME M_J_CPU1_SA_DQ<15>
J 0
(-3290 5110);
DISPLAY 0.659574 (-3290 5110);
PAINT MONO (-3290 5110);
DISPLAY INVISIBLE (-3290 5110);
FORCEPROP 1 LASTPIN (-3300 5100) BN 15
J 0
(-3312 5108);
DISPLAY 0.489362 (-3312 5108);
PAINT GREEN (-3312 5108);
FORCEPROP 2 LAST CDS_LIB mstr_standard
J 0
(-3250 5100);
DISPLAY 0.723404 (-3250 5100);
PAINT MONO (-3250 5100);
DISPLAY INVISIBLE (-3250 5100);
FORCEPROP 1 LAST BODY_TYPE PLUMBING
J 0
(-3250 5150);
DISPLAY 0.872340 (-3250 5150);
PAINT GREEN (-3250 5150);
DISPLAY INVISIBLE (-3250 5150);
FORCEPROP 1 LAST HDL_TAP TRUE
J 0
(-2925 4975);
DISPLAY 0.872340 (-2925 4975);
DISPLAY INVISIBLE (-2925 4975);
FORCEPROP 1 LAST PATH I176
J 0
(-3252 5100);
DISPLAY 0.872340 (-3252 5100);
PAINT GREEN (-3252 5100);
DISPLAY INVISIBLE (-3252 5100);
FORCEADD TAP..1
(-3250 5000);
FORCEPROP 3 LASTPIN (-3300 5000) SIG_NAME M_J_CPU1_SA_DQ<16>
J 0
(-3290 5010);
DISPLAY 0.659574 (-3290 5010);
PAINT MONO (-3290 5010);
DISPLAY INVISIBLE (-3290 5010);
FORCEPROP 1 LASTPIN (-3300 5000) BN 16
J 0
(-3312 5008);
DISPLAY 0.489362 (-3312 5008);
PAINT GREEN (-3312 5008);
FORCEPROP 2 LAST CDS_LIB mstr_standard
J 0
(-3250 5000);
DISPLAY 0.723404 (-3250 5000);
PAINT MONO (-3250 5000);
DISPLAY INVISIBLE (-3250 5000);
FORCEPROP 1 LAST BODY_TYPE PLUMBING
J 0
(-3250 5050);
DISPLAY 0.872340 (-3250 5050);
PAINT GREEN (-3250 5050);
DISPLAY INVISIBLE (-3250 5050);
FORCEPROP 1 LAST HDL_TAP TRUE
J 0
(-2925 4875);
DISPLAY 0.872340 (-2925 4875);
DISPLAY INVISIBLE (-2925 4875);
FORCEPROP 1 LAST PATH I177
J 0
(-3252 5000);
DISPLAY 0.872340 (-3252 5000);
PAINT GREEN (-3252 5000);
DISPLAY INVISIBLE (-3252 5000);
FORCEADD TAP..1
(-3250 4950);
FORCEPROP 3 LASTPIN (-3300 4950) SIG_NAME M_J_CPU1_SA_DQ<17>
J 0
(-3290 4960);
DISPLAY 0.659574 (-3290 4960);
PAINT MONO (-3290 4960);
DISPLAY INVISIBLE (-3290 4960);
FORCEPROP 1 LASTPIN (-3300 4950) BN 17
J 0
(-3312 4958);
DISPLAY 0.489362 (-3312 4958);
PAINT GREEN (-3312 4958);
FORCEPROP 2 LAST CDS_LIB mstr_standard
J 0
(-3250 4950);
DISPLAY 0.723404 (-3250 4950);
PAINT MONO (-3250 4950);
DISPLAY INVISIBLE (-3250 4950);
FORCEPROP 1 LAST BODY_TYPE PLUMBING
J 0
(-3250 5000);
DISPLAY 0.872340 (-3250 5000);
PAINT GREEN (-3250 5000);
DISPLAY INVISIBLE (-3250 5000);
FORCEPROP 1 LAST HDL_TAP TRUE
J 0
(-2925 4825);
DISPLAY 0.872340 (-2925 4825);
DISPLAY INVISIBLE (-2925 4825);
FORCEPROP 1 LAST PATH I178
J 0
(-3252 4950);
DISPLAY 0.872340 (-3252 4950);
PAINT GREEN (-3252 4950);
DISPLAY INVISIBLE (-3252 4950);
FORCEADD TAP..1
(-3250 4900);
FORCEPROP 3 LASTPIN (-3300 4900) SIG_NAME M_J_CPU1_SA_DQ<18>
J 0
(-3290 4910);
DISPLAY 0.659574 (-3290 4910);
PAINT MONO (-3290 4910);
DISPLAY INVISIBLE (-3290 4910);
FORCEPROP 1 LASTPIN (-3300 4900) BN 18
J 0
(-3312 4908);
DISPLAY 0.489362 (-3312 4908);
PAINT GREEN (-3312 4908);
FORCEPROP 2 LAST CDS_LIB mstr_standard
J 0
(-3250 4900);
DISPLAY 0.723404 (-3250 4900);
PAINT MONO (-3250 4900);
DISPLAY INVISIBLE (-3250 4900);
FORCEPROP 1 LAST BODY_TYPE PLUMBING
J 0
(-3250 4950);
DISPLAY 0.872340 (-3250 4950);
PAINT GREEN (-3250 4950);
DISPLAY INVISIBLE (-3250 4950);
FORCEPROP 1 LAST HDL_TAP TRUE
J 0
(-2925 4775);
DISPLAY 0.872340 (-2925 4775);
DISPLAY INVISIBLE (-2925 4775);
FORCEPROP 1 LAST PATH I179
J 0
(-3252 4900);
DISPLAY 0.872340 (-3252 4900);
PAINT GREEN (-3252 4900);
DISPLAY INVISIBLE (-3252 4900);
FORCEADD TAP..1
(-3250 4850);
FORCEPROP 3 LASTPIN (-3300 4850) SIG_NAME M_J_CPU1_SA_DQ<19>
J 0
(-3290 4860);
DISPLAY 0.659574 (-3290 4860);
PAINT MONO (-3290 4860);
DISPLAY INVISIBLE (-3290 4860);
FORCEPROP 1 LASTPIN (-3300 4850) BN 19
J 0
(-3312 4858);
DISPLAY 0.489362 (-3312 4858);
PAINT GREEN (-3312 4858);
FORCEPROP 2 LAST CDS_LIB mstr_standard
J 0
(-3250 4850);
DISPLAY 0.723404 (-3250 4850);
PAINT MONO (-3250 4850);
DISPLAY INVISIBLE (-3250 4850);
FORCEPROP 1 LAST BODY_TYPE PLUMBING
J 0
(-3250 4900);
DISPLAY 0.872340 (-3250 4900);
PAINT GREEN (-3250 4900);
DISPLAY INVISIBLE (-3250 4900);
FORCEPROP 1 LAST HDL_TAP TRUE
J 0
(-2925 4725);
DISPLAY 0.872340 (-2925 4725);
DISPLAY INVISIBLE (-2925 4725);
FORCEPROP 1 LAST PATH I180
J 0
(-3252 4850);
DISPLAY 0.872340 (-3252 4850);
PAINT GREEN (-3252 4850);
DISPLAY INVISIBLE (-3252 4850);
FORCEADD TAP..1
(-3250 4800);
FORCEPROP 3 LASTPIN (-3300 4800) SIG_NAME M_J_CPU1_SA_DQ<20>
J 0
(-3290 4810);
DISPLAY 0.659574 (-3290 4810);
PAINT MONO (-3290 4810);
DISPLAY INVISIBLE (-3290 4810);
FORCEPROP 1 LASTPIN (-3300 4800) BN 20
J 0
(-3312 4808);
DISPLAY 0.489362 (-3312 4808);
PAINT GREEN (-3312 4808);
FORCEPROP 2 LAST CDS_LIB mstr_standard
J 0
(-3250 4800);
DISPLAY 0.723404 (-3250 4800);
PAINT MONO (-3250 4800);
DISPLAY INVISIBLE (-3250 4800);
FORCEPROP 1 LAST BODY_TYPE PLUMBING
J 0
(-3250 4850);
DISPLAY 0.872340 (-3250 4850);
PAINT GREEN (-3250 4850);
DISPLAY INVISIBLE (-3250 4850);
FORCEPROP 1 LAST HDL_TAP TRUE
J 0
(-2925 4675);
DISPLAY 0.872340 (-2925 4675);
DISPLAY INVISIBLE (-2925 4675);
FORCEPROP 1 LAST PATH I181
J 0
(-3252 4800);
DISPLAY 0.872340 (-3252 4800);
PAINT GREEN (-3252 4800);
DISPLAY INVISIBLE (-3252 4800);
FORCEADD TAP..1
(-3250 4750);
FORCEPROP 3 LASTPIN (-3300 4750) SIG_NAME M_J_CPU1_SA_DQ<21>
J 0
(-3290 4760);
DISPLAY 0.659574 (-3290 4760);
PAINT MONO (-3290 4760);
DISPLAY INVISIBLE (-3290 4760);
FORCEPROP 1 LASTPIN (-3300 4750) BN 21
J 0
(-3312 4758);
DISPLAY 0.489362 (-3312 4758);
PAINT GREEN (-3312 4758);
FORCEPROP 2 LAST CDS_LIB mstr_standard
J 0
(-3250 4750);
DISPLAY 0.723404 (-3250 4750);
PAINT MONO (-3250 4750);
DISPLAY INVISIBLE (-3250 4750);
FORCEPROP 1 LAST BODY_TYPE PLUMBING
J 0
(-3250 4800);
DISPLAY 0.872340 (-3250 4800);
PAINT GREEN (-3250 4800);
DISPLAY INVISIBLE (-3250 4800);
FORCEPROP 1 LAST HDL_TAP TRUE
J 0
(-2925 4625);
DISPLAY 0.872340 (-2925 4625);
DISPLAY INVISIBLE (-2925 4625);
FORCEPROP 1 LAST PATH I182
J 0
(-3252 4750);
DISPLAY 0.872340 (-3252 4750);
PAINT GREEN (-3252 4750);
DISPLAY INVISIBLE (-3252 4750);
FORCEADD TAP..1
(-3250 4650);
FORCEPROP 3 LASTPIN (-3300 4650) SIG_NAME M_J_CPU1_SA_DQ<23>
J 0
(-3290 4660);
DISPLAY 0.659574 (-3290 4660);
PAINT MONO (-3290 4660);
DISPLAY INVISIBLE (-3290 4660);
FORCEPROP 1 LASTPIN (-3300 4650) BN 23
J 0
(-3312 4658);
DISPLAY 0.489362 (-3312 4658);
PAINT GREEN (-3312 4658);
FORCEPROP 2 LAST CDS_LIB mstr_standard
J 0
(-3250 4650);
DISPLAY 0.723404 (-3250 4650);
PAINT MONO (-3250 4650);
DISPLAY INVISIBLE (-3250 4650);
FORCEPROP 1 LAST BODY_TYPE PLUMBING
J 0
(-3250 4700);
DISPLAY 0.872340 (-3250 4700);
PAINT GREEN (-3250 4700);
DISPLAY INVISIBLE (-3250 4700);
FORCEPROP 1 LAST HDL_TAP TRUE
J 0
(-2925 4525);
DISPLAY 0.872340 (-2925 4525);
DISPLAY INVISIBLE (-2925 4525);
FORCEPROP 1 LAST PATH I183
J 0
(-3252 4650);
DISPLAY 0.872340 (-3252 4650);
PAINT GREEN (-3252 4650);
DISPLAY INVISIBLE (-3252 4650);
FORCEADD TAP..1
(-3250 4700);
FORCEPROP 3 LASTPIN (-3300 4700) SIG_NAME M_J_CPU1_SA_DQ<22>
J 0
(-3290 4710);
DISPLAY 0.659574 (-3290 4710);
PAINT MONO (-3290 4710);
DISPLAY INVISIBLE (-3290 4710);
FORCEPROP 1 LASTPIN (-3300 4700) BN 22
J 0
(-3312 4708);
DISPLAY 0.489362 (-3312 4708);
PAINT GREEN (-3312 4708);
FORCEPROP 2 LAST CDS_LIB mstr_standard
J 0
(-3250 4700);
DISPLAY 0.723404 (-3250 4700);
PAINT MONO (-3250 4700);
DISPLAY INVISIBLE (-3250 4700);
FORCEPROP 1 LAST BODY_TYPE PLUMBING
J 0
(-3250 4750);
DISPLAY 0.872340 (-3250 4750);
PAINT GREEN (-3250 4750);
DISPLAY INVISIBLE (-3250 4750);
FORCEPROP 1 LAST HDL_TAP TRUE
J 0
(-2925 4575);
DISPLAY 0.872340 (-2925 4575);
DISPLAY INVISIBLE (-2925 4575);
FORCEPROP 1 LAST PATH I184
J 0
(-3252 4700);
DISPLAY 0.872340 (-3252 4700);
PAINT GREEN (-3252 4700);
DISPLAY INVISIBLE (-3252 4700);
FORCEADD TAP..1
(-3250 4500);
FORCEPROP 3 LASTPIN (-3300 4500) SIG_NAME M_J_CPU1_SA_DQ<25>
J 0
(-3290 4510);
DISPLAY 0.659574 (-3290 4510);
PAINT MONO (-3290 4510);
DISPLAY INVISIBLE (-3290 4510);
FORCEPROP 1 LASTPIN (-3300 4500) BN 25
J 0
(-3312 4508);
DISPLAY 0.489362 (-3312 4508);
PAINT GREEN (-3312 4508);
FORCEPROP 2 LAST CDS_LIB mstr_standard
J 0
(-3250 4500);
DISPLAY 0.723404 (-3250 4500);
PAINT MONO (-3250 4500);
DISPLAY INVISIBLE (-3250 4500);
FORCEPROP 1 LAST BODY_TYPE PLUMBING
J 0
(-3250 4550);
DISPLAY 0.872340 (-3250 4550);
PAINT GREEN (-3250 4550);
DISPLAY INVISIBLE (-3250 4550);
FORCEPROP 1 LAST HDL_TAP TRUE
J 0
(-2925 4375);
DISPLAY 0.872340 (-2925 4375);
DISPLAY INVISIBLE (-2925 4375);
FORCEPROP 1 LAST PATH I185
J 0
(-3252 4500);
DISPLAY 0.872340 (-3252 4500);
PAINT GREEN (-3252 4500);
DISPLAY INVISIBLE (-3252 4500);
FORCEADD TAP..1
(-3250 4550);
FORCEPROP 3 LASTPIN (-3300 4550) SIG_NAME M_J_CPU1_SA_DQ<24>
J 0
(-3290 4560);
DISPLAY 0.659574 (-3290 4560);
PAINT MONO (-3290 4560);
DISPLAY INVISIBLE (-3290 4560);
FORCEPROP 1 LASTPIN (-3300 4550) BN 24
J 0
(-3312 4558);
DISPLAY 0.489362 (-3312 4558);
PAINT GREEN (-3312 4558);
FORCEPROP 2 LAST CDS_LIB mstr_standard
J 0
(-3250 4550);
DISPLAY 0.723404 (-3250 4550);
PAINT MONO (-3250 4550);
DISPLAY INVISIBLE (-3250 4550);
FORCEPROP 1 LAST BODY_TYPE PLUMBING
J 0
(-3250 4600);
DISPLAY 0.872340 (-3250 4600);
PAINT GREEN (-3250 4600);
DISPLAY INVISIBLE (-3250 4600);
FORCEPROP 1 LAST HDL_TAP TRUE
J 0
(-2925 4425);
DISPLAY 0.872340 (-2925 4425);
DISPLAY INVISIBLE (-2925 4425);
FORCEPROP 1 LAST PATH I186
J 0
(-3252 4550);
DISPLAY 0.872340 (-3252 4550);
PAINT GREEN (-3252 4550);
DISPLAY INVISIBLE (-3252 4550);
FORCEADD TAP..1
(-3250 4450);
FORCEPROP 3 LASTPIN (-3300 4450) SIG_NAME M_J_CPU1_SA_DQ<26>
J 0
(-3290 4460);
DISPLAY 0.659574 (-3290 4460);
PAINT MONO (-3290 4460);
DISPLAY INVISIBLE (-3290 4460);
FORCEPROP 1 LASTPIN (-3300 4450) BN 26
J 0
(-3312 4458);
DISPLAY 0.489362 (-3312 4458);
PAINT GREEN (-3312 4458);
FORCEPROP 2 LAST CDS_LIB mstr_standard
J 0
(-3250 4450);
DISPLAY 0.723404 (-3250 4450);
PAINT MONO (-3250 4450);
DISPLAY INVISIBLE (-3250 4450);
FORCEPROP 1 LAST BODY_TYPE PLUMBING
J 0
(-3250 4500);
DISPLAY 0.872340 (-3250 4500);
PAINT GREEN (-3250 4500);
DISPLAY INVISIBLE (-3250 4500);
FORCEPROP 1 LAST HDL_TAP TRUE
J 0
(-2925 4325);
DISPLAY 0.872340 (-2925 4325);
DISPLAY INVISIBLE (-2925 4325);
FORCEPROP 1 LAST PATH I187
J 0
(-3252 4450);
DISPLAY 0.872340 (-3252 4450);
PAINT GREEN (-3252 4450);
DISPLAY INVISIBLE (-3252 4450);
FORCEADD TAP..1
(-3250 4400);
FORCEPROP 3 LASTPIN (-3300 4400) SIG_NAME M_J_CPU1_SA_DQ<27>
J 0
(-3290 4410);
DISPLAY 0.659574 (-3290 4410);
PAINT MONO (-3290 4410);
DISPLAY INVISIBLE (-3290 4410);
FORCEPROP 1 LASTPIN (-3300 4400) BN 27
J 0
(-3312 4408);
DISPLAY 0.489362 (-3312 4408);
PAINT GREEN (-3312 4408);
FORCEPROP 2 LAST CDS_LIB mstr_standard
J 0
(-3250 4400);
DISPLAY 0.723404 (-3250 4400);
PAINT MONO (-3250 4400);
DISPLAY INVISIBLE (-3250 4400);
FORCEPROP 1 LAST BODY_TYPE PLUMBING
J 0
(-3250 4450);
DISPLAY 0.872340 (-3250 4450);
PAINT GREEN (-3250 4450);
DISPLAY INVISIBLE (-3250 4450);
FORCEPROP 1 LAST HDL_TAP TRUE
J 0
(-2925 4275);
DISPLAY 0.872340 (-2925 4275);
DISPLAY INVISIBLE (-2925 4275);
FORCEPROP 1 LAST PATH I188
J 0
(-3252 4400);
DISPLAY 0.872340 (-3252 4400);
PAINT GREEN (-3252 4400);
DISPLAY INVISIBLE (-3252 4400);
FORCEADD TAP..1
(-3250 4350);
FORCEPROP 3 LASTPIN (-3300 4350) SIG_NAME M_J_CPU1_SA_DQ<28>
J 0
(-3290 4360);
DISPLAY 0.659574 (-3290 4360);
PAINT MONO (-3290 4360);
DISPLAY INVISIBLE (-3290 4360);
FORCEPROP 1 LASTPIN (-3300 4350) BN 28
J 0
(-3312 4358);
DISPLAY 0.489362 (-3312 4358);
PAINT GREEN (-3312 4358);
FORCEPROP 2 LAST CDS_LIB mstr_standard
J 0
(-3250 4350);
DISPLAY 0.723404 (-3250 4350);
PAINT MONO (-3250 4350);
DISPLAY INVISIBLE (-3250 4350);
FORCEPROP 1 LAST BODY_TYPE PLUMBING
J 0
(-3250 4400);
DISPLAY 0.872340 (-3250 4400);
PAINT GREEN (-3250 4400);
DISPLAY INVISIBLE (-3250 4400);
FORCEPROP 1 LAST HDL_TAP TRUE
J 0
(-2925 4225);
DISPLAY 0.872340 (-2925 4225);
DISPLAY INVISIBLE (-2925 4225);
FORCEPROP 1 LAST PATH I189
J 0
(-3252 4350);
DISPLAY 0.872340 (-3252 4350);
PAINT GREEN (-3252 4350);
DISPLAY INVISIBLE (-3252 4350);
FORCEADD TAP..1
(-3250 4300);
FORCEPROP 3 LASTPIN (-3300 4300) SIG_NAME M_J_CPU1_SA_DQ<29>
J 0
(-3290 4310);
DISPLAY 0.659574 (-3290 4310);
PAINT MONO (-3290 4310);
DISPLAY INVISIBLE (-3290 4310);
FORCEPROP 1 LASTPIN (-3300 4300) BN 29
J 0
(-3312 4308);
DISPLAY 0.489362 (-3312 4308);
PAINT GREEN (-3312 4308);
FORCEPROP 2 LAST CDS_LIB mstr_standard
J 0
(-3250 4300);
DISPLAY 0.723404 (-3250 4300);
PAINT MONO (-3250 4300);
DISPLAY INVISIBLE (-3250 4300);
FORCEPROP 1 LAST BODY_TYPE PLUMBING
J 0
(-3250 4350);
DISPLAY 0.872340 (-3250 4350);
PAINT GREEN (-3250 4350);
DISPLAY INVISIBLE (-3250 4350);
FORCEPROP 1 LAST HDL_TAP TRUE
J 0
(-2925 4175);
DISPLAY 0.872340 (-2925 4175);
DISPLAY INVISIBLE (-2925 4175);
FORCEPROP 1 LAST PATH I190
J 0
(-3252 4300);
DISPLAY 0.872340 (-3252 4300);
PAINT GREEN (-3252 4300);
DISPLAY INVISIBLE (-3252 4300);
FORCEADD TAP..1
(-3250 4250);
FORCEPROP 3 LASTPIN (-3300 4250) SIG_NAME M_J_CPU1_SA_DQ<30>
J 0
(-3290 4260);
DISPLAY 0.659574 (-3290 4260);
PAINT MONO (-3290 4260);
DISPLAY INVISIBLE (-3290 4260);
FORCEPROP 1 LASTPIN (-3300 4250) BN 30
J 0
(-3312 4258);
DISPLAY 0.489362 (-3312 4258);
PAINT GREEN (-3312 4258);
FORCEPROP 2 LAST CDS_LIB mstr_standard
J 0
(-3250 4250);
DISPLAY 0.723404 (-3250 4250);
PAINT MONO (-3250 4250);
DISPLAY INVISIBLE (-3250 4250);
FORCEPROP 1 LAST BODY_TYPE PLUMBING
J 0
(-3250 4300);
DISPLAY 0.872340 (-3250 4300);
PAINT GREEN (-3250 4300);
DISPLAY INVISIBLE (-3250 4300);
FORCEPROP 1 LAST HDL_TAP TRUE
J 0
(-2925 4125);
DISPLAY 0.872340 (-2925 4125);
DISPLAY INVISIBLE (-2925 4125);
FORCEPROP 1 LAST PATH I191
J 0
(-3252 4250);
DISPLAY 0.872340 (-3252 4250);
PAINT GREEN (-3252 4250);
DISPLAY INVISIBLE (-3252 4250);
FORCEADD TAP..1
(-3250 4100);
FORCEPROP 3 LASTPIN (-3300 4100) SIG_NAME M_J_CPU1_SB_DQ<0>
J 0
(-3290 4110);
DISPLAY 0.659574 (-3290 4110);
PAINT MONO (-3290 4110);
DISPLAY INVISIBLE (-3290 4110);
FORCEPROP 1 LASTPIN (-3300 4100) BN 0
J 0
(-3312 4108);
DISPLAY 0.489362 (-3312 4108);
PAINT GREEN (-3312 4108);
FORCEPROP 2 LAST CDS_LIB mstr_standard
J 0
(-3250 4100);
DISPLAY 0.723404 (-3250 4100);
PAINT MONO (-3250 4100);
DISPLAY INVISIBLE (-3250 4100);
FORCEPROP 1 LAST BODY_TYPE PLUMBING
J 0
(-3250 4150);
DISPLAY 0.872340 (-3250 4150);
PAINT GREEN (-3250 4150);
DISPLAY INVISIBLE (-3250 4150);
FORCEPROP 1 LAST HDL_TAP TRUE
J 0
(-2925 3975);
DISPLAY 0.872340 (-2925 3975);
DISPLAY INVISIBLE (-2925 3975);
FORCEPROP 1 LAST PATH I192
J 0
(-3252 4100);
DISPLAY 0.872340 (-3252 4100);
PAINT GREEN (-3252 4100);
DISPLAY INVISIBLE (-3252 4100);
FORCEADD TAP..1
(-3250 4200);
FORCEPROP 3 LASTPIN (-3300 4200) SIG_NAME M_J_CPU1_SA_DQ<31>
J 0
(-3290 4210);
DISPLAY 0.659574 (-3290 4210);
PAINT MONO (-3290 4210);
DISPLAY INVISIBLE (-3290 4210);
FORCEPROP 1 LASTPIN (-3300 4200) BN 31
J 0
(-3312 4208);
DISPLAY 0.489362 (-3312 4208);
PAINT GREEN (-3312 4208);
FORCEPROP 2 LAST CDS_LIB mstr_standard
J 0
(-3250 4200);
DISPLAY 0.723404 (-3250 4200);
PAINT MONO (-3250 4200);
DISPLAY INVISIBLE (-3250 4200);
FORCEPROP 1 LAST BODY_TYPE PLUMBING
J 0
(-3250 4250);
DISPLAY 0.872340 (-3250 4250);
PAINT GREEN (-3250 4250);
DISPLAY INVISIBLE (-3250 4250);
FORCEPROP 1 LAST HDL_TAP TRUE
J 0
(-2925 4075);
DISPLAY 0.872340 (-2925 4075);
DISPLAY INVISIBLE (-2925 4075);
FORCEPROP 1 LAST PATH I193
J 0
(-3252 4200);
DISPLAY 0.872340 (-3252 4200);
PAINT GREEN (-3252 4200);
DISPLAY INVISIBLE (-3252 4200);
FORCEADD OFFPAGE..3
(-2525 4125);
FORCEPROP 2 LAST $XR0 107 
J 0
(-2311 4125);
DISPLAY 0.638298 (-2311 4125);
PAINT MONO (-2311 4125);
FORCEPROP 2 LAST CDS_LIB mstr_standard
J 0
(-2525 4125);
DISPLAY 0.723404 (-2525 4125);
PAINT MONO (-2525 4125);
DISPLAY INVISIBLE (-2525 4125);
FORCEPROP 1 LAST OFFPAGE TRUE
J 0
(-2200 4000);
DISPLAY 0.872340 (-2200 4000);
PAINT GREEN (-2200 4000);
DISPLAY INVISIBLE (-2200 4000);
FORCEPROP 1 LAST COMMENT_BODY TRUE
J 0
(-2575 4025);
DISPLAY 0.872340 (-2575 4025);
PAINT GREEN (-2575 4025);
DISPLAY INVISIBLE (-2575 4025);
FORCEPROP 2 LAST PATH I194
J 0
(-2300 4175);
DISPLAY 1.021277 (-2300 4175);
DISPLAY INVISIBLE (-2300 4175);
FORCEADD OFFPAGE..6
R 2
(-2650 2350);
FORCEPROP 2 LAST $XR0 107 
J 0
(-2436 2350);
DISPLAY 0.638298 (-2436 2350);
PAINT MONO (-2436 2350);
FORCEPROP 2 LAST CDS_LIB mstr_standard
J 2
(-2650 2350);
DISPLAY 0.723404 (-2650 2350);
PAINT MONO (-2650 2350);
DISPLAY INVISIBLE (-2650 2350);
FORCEPROP 1 LAST OFFPAGE TRUE
J 2
(-2975 2225);
DISPLAY 0.872340 (-2975 2225);
PAINT GREEN (-2975 2225);
DISPLAY INVISIBLE (-2975 2225);
FORCEPROP 1 LAST COMMENT_BODY TRUE
J 2
(-2750 2275);
DISPLAY 0.872340 (-2750 2275);
PAINT GREEN (-2750 2275);
DISPLAY INVISIBLE (-2750 2275);
FORCEPROP 2 LAST PATH I195
J 0
(-2425 2400);
DISPLAY 1.021277 (-2425 2400);
DISPLAY INVISIBLE (-2425 2400);
FORCEADD TAP..1
(-3250 4000);
FORCEPROP 3 LASTPIN (-3300 4000) SIG_NAME M_J_CPU1_SB_DQ<2>
J 0
(-3290 4010);
DISPLAY 0.659574 (-3290 4010);
PAINT MONO (-3290 4010);
DISPLAY INVISIBLE (-3290 4010);
FORCEPROP 1 LASTPIN (-3300 4000) BN 2
J 0
(-3312 4008);
DISPLAY 0.489362 (-3312 4008);
PAINT GREEN (-3312 4008);
FORCEPROP 2 LAST CDS_LIB mstr_standard
J 0
(-3250 4000);
DISPLAY 0.723404 (-3250 4000);
PAINT MONO (-3250 4000);
DISPLAY INVISIBLE (-3250 4000);
FORCEPROP 1 LAST BODY_TYPE PLUMBING
J 0
(-3250 4050);
DISPLAY 0.872340 (-3250 4050);
PAINT GREEN (-3250 4050);
DISPLAY INVISIBLE (-3250 4050);
FORCEPROP 1 LAST HDL_TAP TRUE
J 0
(-2925 3875);
DISPLAY 0.872340 (-2925 3875);
DISPLAY INVISIBLE (-2925 3875);
FORCEPROP 1 LAST PATH I196
J 0
(-3252 4000);
DISPLAY 0.872340 (-3252 4000);
PAINT GREEN (-3252 4000);
DISPLAY INVISIBLE (-3252 4000);
FORCEADD TAP..1
(-3250 4050);
FORCEPROP 3 LASTPIN (-3300 4050) SIG_NAME M_J_CPU1_SB_DQ<1>
J 0
(-3290 4060);
DISPLAY 0.659574 (-3290 4060);
PAINT MONO (-3290 4060);
DISPLAY INVISIBLE (-3290 4060);
FORCEPROP 1 LASTPIN (-3300 4050) BN 1
J 0
(-3312 4058);
DISPLAY 0.489362 (-3312 4058);
PAINT GREEN (-3312 4058);
FORCEPROP 2 LAST CDS_LIB mstr_standard
J 0
(-3250 4050);
DISPLAY 0.723404 (-3250 4050);
PAINT MONO (-3250 4050);
DISPLAY INVISIBLE (-3250 4050);
FORCEPROP 1 LAST BODY_TYPE PLUMBING
J 0
(-3250 4100);
DISPLAY 0.872340 (-3250 4100);
PAINT GREEN (-3250 4100);
DISPLAY INVISIBLE (-3250 4100);
FORCEPROP 1 LAST HDL_TAP TRUE
J 0
(-2925 3925);
DISPLAY 0.872340 (-2925 3925);
DISPLAY INVISIBLE (-2925 3925);
FORCEPROP 1 LAST PATH I197
J 0
(-3252 4050);
DISPLAY 0.872340 (-3252 4050);
PAINT GREEN (-3252 4050);
DISPLAY INVISIBLE (-3252 4050);
FORCEADD TAP..1
(-3250 3900);
FORCEPROP 3 LASTPIN (-3300 3900) SIG_NAME M_J_CPU1_SB_DQ<4>
J 0
(-3290 3910);
DISPLAY 0.659574 (-3290 3910);
PAINT MONO (-3290 3910);
DISPLAY INVISIBLE (-3290 3910);
FORCEPROP 1 LASTPIN (-3300 3900) BN 4
J 0
(-3312 3908);
DISPLAY 0.489362 (-3312 3908);
PAINT GREEN (-3312 3908);
FORCEPROP 2 LAST CDS_LIB mstr_standard
J 0
(-3250 3900);
DISPLAY 0.723404 (-3250 3900);
PAINT MONO (-3250 3900);
DISPLAY INVISIBLE (-3250 3900);
FORCEPROP 1 LAST BODY_TYPE PLUMBING
J 0
(-3250 3950);
DISPLAY 0.872340 (-3250 3950);
PAINT GREEN (-3250 3950);
DISPLAY INVISIBLE (-3250 3950);
FORCEPROP 1 LAST HDL_TAP TRUE
J 0
(-2925 3775);
DISPLAY 0.872340 (-2925 3775);
DISPLAY INVISIBLE (-2925 3775);
FORCEPROP 1 LAST PATH I198
J 0
(-3252 3900);
DISPLAY 0.872340 (-3252 3900);
PAINT GREEN (-3252 3900);
DISPLAY INVISIBLE (-3252 3900);
FORCEADD TAP..1
(-3250 3950);
FORCEPROP 3 LASTPIN (-3300 3950) SIG_NAME M_J_CPU1_SB_DQ<3>
J 0
(-3290 3960);
DISPLAY 0.659574 (-3290 3960);
PAINT MONO (-3290 3960);
DISPLAY INVISIBLE (-3290 3960);
FORCEPROP 1 LASTPIN (-3300 3950) BN 3
J 0
(-3312 3958);
DISPLAY 0.489362 (-3312 3958);
PAINT GREEN (-3312 3958);
FORCEPROP 2 LAST CDS_LIB mstr_standard
J 0
(-3250 3950);
DISPLAY 0.723404 (-3250 3950);
PAINT MONO (-3250 3950);
DISPLAY INVISIBLE (-3250 3950);
FORCEPROP 1 LAST BODY_TYPE PLUMBING
J 0
(-3250 4000);
DISPLAY 0.872340 (-3250 4000);
PAINT GREEN (-3250 4000);
DISPLAY INVISIBLE (-3250 4000);
FORCEPROP 1 LAST HDL_TAP TRUE
J 0
(-2925 3825);
DISPLAY 0.872340 (-2925 3825);
DISPLAY INVISIBLE (-2925 3825);
FORCEPROP 1 LAST PATH I199
J 0
(-3252 3950);
DISPLAY 0.872340 (-3252 3950);
PAINT GREEN (-3252 3950);
DISPLAY INVISIBLE (-3252 3950);
FORCEADD TAP..1
(-3250 3850);
FORCEPROP 3 LASTPIN (-3300 3850) SIG_NAME M_J_CPU1_SB_DQ<5>
J 0
(-3290 3860);
DISPLAY 0.659574 (-3290 3860);
PAINT MONO (-3290 3860);
DISPLAY INVISIBLE (-3290 3860);
FORCEPROP 1 LASTPIN (-3300 3850) BN 5
J 0
(-3312 3858);
DISPLAY 0.489362 (-3312 3858);
PAINT GREEN (-3312 3858);
FORCEPROP 2 LAST CDS_LIB mstr_standard
J 0
(-3250 3850);
DISPLAY 0.723404 (-3250 3850);
PAINT MONO (-3250 3850);
DISPLAY INVISIBLE (-3250 3850);
FORCEPROP 1 LAST BODY_TYPE PLUMBING
J 0
(-3250 3900);
DISPLAY 0.872340 (-3250 3900);
PAINT GREEN (-3250 3900);
DISPLAY INVISIBLE (-3250 3900);
FORCEPROP 1 LAST HDL_TAP TRUE
J 0
(-2925 3725);
DISPLAY 0.872340 (-2925 3725);
DISPLAY INVISIBLE (-2925 3725);
FORCEPROP 1 LAST PATH I200
J 0
(-3252 3850);
DISPLAY 0.872340 (-3252 3850);
PAINT GREEN (-3252 3850);
DISPLAY INVISIBLE (-3252 3850);
FORCEADD TAP..1
(-3250 3750);
FORCEPROP 3 LASTPIN (-3300 3750) SIG_NAME M_J_CPU1_SB_DQ<7>
J 0
(-3290 3760);
DISPLAY 0.659574 (-3290 3760);
PAINT MONO (-3290 3760);
DISPLAY INVISIBLE (-3290 3760);
FORCEPROP 1 LASTPIN (-3300 3750) BN 7
J 0
(-3312 3758);
DISPLAY 0.489362 (-3312 3758);
PAINT GREEN (-3312 3758);
FORCEPROP 2 LAST CDS_LIB mstr_standard
J 0
(-3250 3750);
DISPLAY 0.723404 (-3250 3750);
PAINT MONO (-3250 3750);
DISPLAY INVISIBLE (-3250 3750);
FORCEPROP 1 LAST BODY_TYPE PLUMBING
J 0
(-3250 3800);
DISPLAY 0.872340 (-3250 3800);
PAINT GREEN (-3250 3800);
DISPLAY INVISIBLE (-3250 3800);
FORCEPROP 1 LAST HDL_TAP TRUE
J 0
(-2925 3625);
DISPLAY 0.872340 (-2925 3625);
DISPLAY INVISIBLE (-2925 3625);
FORCEPROP 1 LAST PATH I201
J 0
(-3252 3750);
DISPLAY 0.872340 (-3252 3750);
PAINT GREEN (-3252 3750);
DISPLAY INVISIBLE (-3252 3750);
FORCEADD TAP..1
(-3250 3800);
FORCEPROP 3 LASTPIN (-3300 3800) SIG_NAME M_J_CPU1_SB_DQ<6>
J 0
(-3290 3810);
DISPLAY 0.659574 (-3290 3810);
PAINT MONO (-3290 3810);
DISPLAY INVISIBLE (-3290 3810);
FORCEPROP 1 LASTPIN (-3300 3800) BN 6
J 0
(-3312 3808);
DISPLAY 0.489362 (-3312 3808);
PAINT GREEN (-3312 3808);
FORCEPROP 2 LAST CDS_LIB mstr_standard
J 0
(-3250 3800);
DISPLAY 0.723404 (-3250 3800);
PAINT MONO (-3250 3800);
DISPLAY INVISIBLE (-3250 3800);
FORCEPROP 1 LAST BODY_TYPE PLUMBING
J 0
(-3250 3850);
DISPLAY 0.872340 (-3250 3850);
PAINT GREEN (-3250 3850);
DISPLAY INVISIBLE (-3250 3850);
FORCEPROP 1 LAST HDL_TAP TRUE
J 0
(-2925 3675);
DISPLAY 0.872340 (-2925 3675);
DISPLAY INVISIBLE (-2925 3675);
FORCEPROP 1 LAST PATH I202
J 0
(-3252 3800);
DISPLAY 0.872340 (-3252 3800);
PAINT GREEN (-3252 3800);
DISPLAY INVISIBLE (-3252 3800);
FORCEADD TAP..1
(-3250 3650);
FORCEPROP 3 LASTPIN (-3300 3650) SIG_NAME M_J_CPU1_SB_DQ<8>
J 0
(-3290 3660);
DISPLAY 0.659574 (-3290 3660);
PAINT MONO (-3290 3660);
DISPLAY INVISIBLE (-3290 3660);
FORCEPROP 1 LASTPIN (-3300 3650) BN 8
J 0
(-3312 3658);
DISPLAY 0.489362 (-3312 3658);
PAINT GREEN (-3312 3658);
FORCEPROP 2 LAST CDS_LIB mstr_standard
J 0
(-3250 3650);
DISPLAY 0.723404 (-3250 3650);
PAINT MONO (-3250 3650);
DISPLAY INVISIBLE (-3250 3650);
FORCEPROP 1 LAST BODY_TYPE PLUMBING
J 0
(-3250 3700);
DISPLAY 0.872340 (-3250 3700);
PAINT GREEN (-3250 3700);
DISPLAY INVISIBLE (-3250 3700);
FORCEPROP 1 LAST HDL_TAP TRUE
J 0
(-2925 3525);
DISPLAY 0.872340 (-2925 3525);
DISPLAY INVISIBLE (-2925 3525);
FORCEPROP 1 LAST PATH I203
J 0
(-3252 3650);
DISPLAY 0.872340 (-3252 3650);
PAINT GREEN (-3252 3650);
DISPLAY INVISIBLE (-3252 3650);
FORCEADD TAP..1
(-3250 3600);
FORCEPROP 3 LASTPIN (-3300 3600) SIG_NAME M_J_CPU1_SB_DQ<9>
J 0
(-3290 3610);
DISPLAY 0.659574 (-3290 3610);
PAINT MONO (-3290 3610);
DISPLAY INVISIBLE (-3290 3610);
FORCEPROP 1 LASTPIN (-3300 3600) BN 9
J 0
(-3312 3608);
DISPLAY 0.489362 (-3312 3608);
PAINT GREEN (-3312 3608);
FORCEPROP 2 LAST CDS_LIB mstr_standard
J 0
(-3250 3600);
DISPLAY 0.723404 (-3250 3600);
PAINT MONO (-3250 3600);
DISPLAY INVISIBLE (-3250 3600);
FORCEPROP 1 LAST BODY_TYPE PLUMBING
J 0
(-3250 3650);
DISPLAY 0.872340 (-3250 3650);
PAINT GREEN (-3250 3650);
DISPLAY INVISIBLE (-3250 3650);
FORCEPROP 1 LAST HDL_TAP TRUE
J 0
(-2925 3475);
DISPLAY 0.872340 (-2925 3475);
DISPLAY INVISIBLE (-2925 3475);
FORCEPROP 1 LAST PATH I204
J 0
(-3252 3600);
DISPLAY 0.872340 (-3252 3600);
PAINT GREEN (-3252 3600);
DISPLAY INVISIBLE (-3252 3600);
FORCEADD TAP..1
(-3250 3500);
FORCEPROP 3 LASTPIN (-3300 3500) SIG_NAME M_J_CPU1_SB_DQ<11>
J 0
(-3290 3510);
DISPLAY 0.659574 (-3290 3510);
PAINT MONO (-3290 3510);
DISPLAY INVISIBLE (-3290 3510);
FORCEPROP 1 LASTPIN (-3300 3500) BN 11
J 0
(-3312 3508);
DISPLAY 0.489362 (-3312 3508);
PAINT GREEN (-3312 3508);
FORCEPROP 2 LAST CDS_LIB mstr_standard
J 0
(-3250 3500);
DISPLAY 0.723404 (-3250 3500);
PAINT MONO (-3250 3500);
DISPLAY INVISIBLE (-3250 3500);
FORCEPROP 1 LAST BODY_TYPE PLUMBING
J 0
(-3250 3550);
DISPLAY 0.872340 (-3250 3550);
PAINT GREEN (-3250 3550);
DISPLAY INVISIBLE (-3250 3550);
FORCEPROP 1 LAST HDL_TAP TRUE
J 0
(-2925 3375);
DISPLAY 0.872340 (-2925 3375);
DISPLAY INVISIBLE (-2925 3375);
FORCEPROP 1 LAST PATH I205
J 0
(-3252 3500);
DISPLAY 0.872340 (-3252 3500);
PAINT GREEN (-3252 3500);
DISPLAY INVISIBLE (-3252 3500);
FORCEADD TAP..1
(-3250 3550);
FORCEPROP 3 LASTPIN (-3300 3550) SIG_NAME M_J_CPU1_SB_DQ<10>
J 0
(-3290 3560);
DISPLAY 0.659574 (-3290 3560);
PAINT MONO (-3290 3560);
DISPLAY INVISIBLE (-3290 3560);
FORCEPROP 1 LASTPIN (-3300 3550) BN 10
J 0
(-3312 3558);
DISPLAY 0.489362 (-3312 3558);
PAINT GREEN (-3312 3558);
FORCEPROP 2 LAST CDS_LIB mstr_standard
J 0
(-3250 3550);
DISPLAY 0.723404 (-3250 3550);
PAINT MONO (-3250 3550);
DISPLAY INVISIBLE (-3250 3550);
FORCEPROP 1 LAST BODY_TYPE PLUMBING
J 0
(-3250 3600);
DISPLAY 0.872340 (-3250 3600);
PAINT GREEN (-3250 3600);
DISPLAY INVISIBLE (-3250 3600);
FORCEPROP 1 LAST HDL_TAP TRUE
J 0
(-2925 3425);
DISPLAY 0.872340 (-2925 3425);
DISPLAY INVISIBLE (-2925 3425);
FORCEPROP 1 LAST PATH I206
J 0
(-3252 3550);
DISPLAY 0.872340 (-3252 3550);
PAINT GREEN (-3252 3550);
DISPLAY INVISIBLE (-3252 3550);
FORCEADD TAP..1
(-3250 3450);
FORCEPROP 3 LASTPIN (-3300 3450) SIG_NAME M_J_CPU1_SB_DQ<12>
J 0
(-3290 3460);
DISPLAY 0.659574 (-3290 3460);
PAINT MONO (-3290 3460);
DISPLAY INVISIBLE (-3290 3460);
FORCEPROP 1 LASTPIN (-3300 3450) BN 12
J 0
(-3312 3458);
DISPLAY 0.489362 (-3312 3458);
PAINT GREEN (-3312 3458);
FORCEPROP 2 LAST CDS_LIB mstr_standard
J 0
(-3250 3450);
DISPLAY 0.723404 (-3250 3450);
PAINT MONO (-3250 3450);
DISPLAY INVISIBLE (-3250 3450);
FORCEPROP 1 LAST BODY_TYPE PLUMBING
J 0
(-3250 3500);
DISPLAY 0.872340 (-3250 3500);
PAINT GREEN (-3250 3500);
DISPLAY INVISIBLE (-3250 3500);
FORCEPROP 1 LAST HDL_TAP TRUE
J 0
(-2925 3325);
DISPLAY 0.872340 (-2925 3325);
DISPLAY INVISIBLE (-2925 3325);
FORCEPROP 1 LAST PATH I207
J 0
(-3252 3450);
DISPLAY 0.872340 (-3252 3450);
PAINT GREEN (-3252 3450);
DISPLAY INVISIBLE (-3252 3450);
FORCEADD TAP..1
(-3250 3400);
FORCEPROP 3 LASTPIN (-3300 3400) SIG_NAME M_J_CPU1_SB_DQ<13>
J 0
(-3290 3410);
DISPLAY 0.659574 (-3290 3410);
PAINT MONO (-3290 3410);
DISPLAY INVISIBLE (-3290 3410);
FORCEPROP 1 LASTPIN (-3300 3400) BN 13
J 0
(-3312 3408);
DISPLAY 0.489362 (-3312 3408);
PAINT GREEN (-3312 3408);
FORCEPROP 2 LAST CDS_LIB mstr_standard
J 0
(-3250 3400);
DISPLAY 0.723404 (-3250 3400);
PAINT MONO (-3250 3400);
DISPLAY INVISIBLE (-3250 3400);
FORCEPROP 1 LAST BODY_TYPE PLUMBING
J 0
(-3250 3450);
DISPLAY 0.872340 (-3250 3450);
PAINT GREEN (-3250 3450);
DISPLAY INVISIBLE (-3250 3450);
FORCEPROP 1 LAST HDL_TAP TRUE
J 0
(-2925 3275);
DISPLAY 0.872340 (-2925 3275);
DISPLAY INVISIBLE (-2925 3275);
FORCEPROP 1 LAST PATH I208
J 0
(-3252 3400);
DISPLAY 0.872340 (-3252 3400);
PAINT GREEN (-3252 3400);
DISPLAY INVISIBLE (-3252 3400);
FORCEADD TAP..1
(-3250 3350);
FORCEPROP 3 LASTPIN (-3300 3350) SIG_NAME M_J_CPU1_SB_DQ<14>
J 0
(-3290 3360);
DISPLAY 0.659574 (-3290 3360);
PAINT MONO (-3290 3360);
DISPLAY INVISIBLE (-3290 3360);
FORCEPROP 1 LASTPIN (-3300 3350) BN 14
J 0
(-3312 3358);
DISPLAY 0.489362 (-3312 3358);
PAINT GREEN (-3312 3358);
FORCEPROP 2 LAST CDS_LIB mstr_standard
J 0
(-3250 3350);
DISPLAY 0.723404 (-3250 3350);
PAINT MONO (-3250 3350);
DISPLAY INVISIBLE (-3250 3350);
FORCEPROP 1 LAST BODY_TYPE PLUMBING
J 0
(-3250 3400);
DISPLAY 0.872340 (-3250 3400);
PAINT GREEN (-3250 3400);
DISPLAY INVISIBLE (-3250 3400);
FORCEPROP 1 LAST HDL_TAP TRUE
J 0
(-2925 3225);
DISPLAY 0.872340 (-2925 3225);
DISPLAY INVISIBLE (-2925 3225);
FORCEPROP 1 LAST PATH I209
J 0
(-3252 3350);
DISPLAY 0.872340 (-3252 3350);
PAINT GREEN (-3252 3350);
DISPLAY INVISIBLE (-3252 3350);
FORCEADD TAP..1
(-3250 3300);
FORCEPROP 3 LASTPIN (-3300 3300) SIG_NAME M_J_CPU1_SB_DQ<15>
J 0
(-3290 3310);
DISPLAY 0.659574 (-3290 3310);
PAINT MONO (-3290 3310);
DISPLAY INVISIBLE (-3290 3310);
FORCEPROP 1 LASTPIN (-3300 3300) BN 15
J 0
(-3312 3308);
DISPLAY 0.489362 (-3312 3308);
PAINT GREEN (-3312 3308);
FORCEPROP 2 LAST CDS_LIB mstr_standard
J 0
(-3250 3300);
DISPLAY 0.723404 (-3250 3300);
PAINT MONO (-3250 3300);
DISPLAY INVISIBLE (-3250 3300);
FORCEPROP 1 LAST BODY_TYPE PLUMBING
J 0
(-3250 3350);
DISPLAY 0.872340 (-3250 3350);
PAINT GREEN (-3250 3350);
DISPLAY INVISIBLE (-3250 3350);
FORCEPROP 1 LAST HDL_TAP TRUE
J 0
(-2925 3175);
DISPLAY 0.872340 (-2925 3175);
DISPLAY INVISIBLE (-2925 3175);
FORCEPROP 1 LAST PATH I210
J 0
(-3252 3300);
DISPLAY 0.872340 (-3252 3300);
PAINT GREEN (-3252 3300);
DISPLAY INVISIBLE (-3252 3300);
FORCEADD TAP..1
(-3250 3200);
FORCEPROP 3 LASTPIN (-3300 3200) SIG_NAME M_J_CPU1_SB_DQ<16>
J 0
(-3290 3210);
DISPLAY 0.659574 (-3290 3210);
PAINT MONO (-3290 3210);
DISPLAY INVISIBLE (-3290 3210);
FORCEPROP 1 LASTPIN (-3300 3200) BN 16
J 0
(-3312 3208);
DISPLAY 0.489362 (-3312 3208);
PAINT GREEN (-3312 3208);
FORCEPROP 2 LAST CDS_LIB mstr_standard
J 0
(-3250 3200);
DISPLAY 0.723404 (-3250 3200);
PAINT MONO (-3250 3200);
DISPLAY INVISIBLE (-3250 3200);
FORCEPROP 1 LAST BODY_TYPE PLUMBING
J 0
(-3250 3250);
DISPLAY 0.872340 (-3250 3250);
PAINT GREEN (-3250 3250);
DISPLAY INVISIBLE (-3250 3250);
FORCEPROP 1 LAST HDL_TAP TRUE
J 0
(-2925 3075);
DISPLAY 0.872340 (-2925 3075);
DISPLAY INVISIBLE (-2925 3075);
FORCEPROP 1 LAST PATH I211
J 0
(-3252 3200);
DISPLAY 0.872340 (-3252 3200);
PAINT GREEN (-3252 3200);
DISPLAY INVISIBLE (-3252 3200);
FORCEADD TAP..1
(-3250 3150);
FORCEPROP 3 LASTPIN (-3300 3150) SIG_NAME M_J_CPU1_SB_DQ<17>
J 0
(-3290 3160);
DISPLAY 0.659574 (-3290 3160);
PAINT MONO (-3290 3160);
DISPLAY INVISIBLE (-3290 3160);
FORCEPROP 1 LASTPIN (-3300 3150) BN 17
J 0
(-3312 3158);
DISPLAY 0.489362 (-3312 3158);
PAINT GREEN (-3312 3158);
FORCEPROP 2 LAST CDS_LIB mstr_standard
J 0
(-3250 3150);
DISPLAY 0.723404 (-3250 3150);
PAINT MONO (-3250 3150);
DISPLAY INVISIBLE (-3250 3150);
FORCEPROP 1 LAST BODY_TYPE PLUMBING
J 0
(-3250 3200);
DISPLAY 0.872340 (-3250 3200);
PAINT GREEN (-3250 3200);
DISPLAY INVISIBLE (-3250 3200);
FORCEPROP 1 LAST HDL_TAP TRUE
J 0
(-2925 3025);
DISPLAY 0.872340 (-2925 3025);
DISPLAY INVISIBLE (-2925 3025);
FORCEPROP 1 LAST PATH I212
J 0
(-3252 3150);
DISPLAY 0.872340 (-3252 3150);
PAINT GREEN (-3252 3150);
DISPLAY INVISIBLE (-3252 3150);
FORCEADD TAP..1
(-3250 3100);
FORCEPROP 3 LASTPIN (-3300 3100) SIG_NAME M_J_CPU1_SB_DQ<18>
J 0
(-3290 3110);
DISPLAY 0.659574 (-3290 3110);
PAINT MONO (-3290 3110);
DISPLAY INVISIBLE (-3290 3110);
FORCEPROP 1 LASTPIN (-3300 3100) BN 18
J 0
(-3312 3108);
DISPLAY 0.489362 (-3312 3108);
PAINT GREEN (-3312 3108);
FORCEPROP 2 LAST CDS_LIB mstr_standard
J 0
(-3250 3100);
DISPLAY 0.723404 (-3250 3100);
PAINT MONO (-3250 3100);
DISPLAY INVISIBLE (-3250 3100);
FORCEPROP 1 LAST BODY_TYPE PLUMBING
J 0
(-3250 3150);
DISPLAY 0.872340 (-3250 3150);
PAINT GREEN (-3250 3150);
DISPLAY INVISIBLE (-3250 3150);
FORCEPROP 1 LAST HDL_TAP TRUE
J 0
(-2925 2975);
DISPLAY 0.872340 (-2925 2975);
DISPLAY INVISIBLE (-2925 2975);
FORCEPROP 1 LAST PATH I213
J 0
(-3252 3100);
DISPLAY 0.872340 (-3252 3100);
PAINT GREEN (-3252 3100);
DISPLAY INVISIBLE (-3252 3100);
FORCEADD TAP..1
(-3250 2950);
FORCEPROP 3 LASTPIN (-3300 2950) SIG_NAME M_J_CPU1_SB_DQ<21>
J 0
(-3290 2960);
DISPLAY 0.659574 (-3290 2960);
PAINT MONO (-3290 2960);
DISPLAY INVISIBLE (-3290 2960);
FORCEPROP 1 LASTPIN (-3300 2950) BN 21
J 0
(-3312 2958);
DISPLAY 0.489362 (-3312 2958);
PAINT GREEN (-3312 2958);
FORCEPROP 2 LAST CDS_LIB mstr_standard
J 0
(-3250 2950);
DISPLAY 0.723404 (-3250 2950);
PAINT MONO (-3250 2950);
DISPLAY INVISIBLE (-3250 2950);
FORCEPROP 1 LAST BODY_TYPE PLUMBING
J 0
(-3250 3000);
DISPLAY 0.872340 (-3250 3000);
PAINT GREEN (-3250 3000);
DISPLAY INVISIBLE (-3250 3000);
FORCEPROP 1 LAST HDL_TAP TRUE
J 0
(-2925 2825);
DISPLAY 0.872340 (-2925 2825);
DISPLAY INVISIBLE (-2925 2825);
FORCEPROP 1 LAST PATH I214
J 0
(-3252 2950);
DISPLAY 0.872340 (-3252 2950);
PAINT GREEN (-3252 2950);
DISPLAY INVISIBLE (-3252 2950);
FORCEADD TAP..1
(-3250 3000);
FORCEPROP 3 LASTPIN (-3300 3000) SIG_NAME M_J_CPU1_SB_DQ<20>
J 0
(-3290 3010);
DISPLAY 0.659574 (-3290 3010);
PAINT MONO (-3290 3010);
DISPLAY INVISIBLE (-3290 3010);
FORCEPROP 1 LASTPIN (-3300 3000) BN 20
J 0
(-3312 3008);
DISPLAY 0.489362 (-3312 3008);
PAINT GREEN (-3312 3008);
FORCEPROP 2 LAST CDS_LIB mstr_standard
J 0
(-3250 3000);
DISPLAY 0.723404 (-3250 3000);
PAINT MONO (-3250 3000);
DISPLAY INVISIBLE (-3250 3000);
FORCEPROP 1 LAST BODY_TYPE PLUMBING
J 0
(-3250 3050);
DISPLAY 0.872340 (-3250 3050);
PAINT GREEN (-3250 3050);
DISPLAY INVISIBLE (-3250 3050);
FORCEPROP 1 LAST HDL_TAP TRUE
J 0
(-2925 2875);
DISPLAY 0.872340 (-2925 2875);
DISPLAY INVISIBLE (-2925 2875);
FORCEPROP 1 LAST PATH I215
J 0
(-3252 3000);
DISPLAY 0.872340 (-3252 3000);
PAINT GREEN (-3252 3000);
DISPLAY INVISIBLE (-3252 3000);
FORCEADD TAP..1
(-3250 3050);
FORCEPROP 3 LASTPIN (-3300 3050) SIG_NAME M_J_CPU1_SB_DQ<19>
J 0
(-3290 3060);
DISPLAY 0.659574 (-3290 3060);
PAINT MONO (-3290 3060);
DISPLAY INVISIBLE (-3290 3060);
FORCEPROP 1 LASTPIN (-3300 3050) BN 19
J 0
(-3312 3058);
DISPLAY 0.489362 (-3312 3058);
PAINT GREEN (-3312 3058);
FORCEPROP 2 LAST CDS_LIB mstr_standard
J 0
(-3250 3050);
DISPLAY 0.723404 (-3250 3050);
PAINT MONO (-3250 3050);
DISPLAY INVISIBLE (-3250 3050);
FORCEPROP 1 LAST BODY_TYPE PLUMBING
J 0
(-3250 3100);
DISPLAY 0.872340 (-3250 3100);
PAINT GREEN (-3250 3100);
DISPLAY INVISIBLE (-3250 3100);
FORCEPROP 1 LAST HDL_TAP TRUE
J 0
(-2925 2925);
DISPLAY 0.872340 (-2925 2925);
DISPLAY INVISIBLE (-2925 2925);
FORCEPROP 1 LAST PATH I216
J 0
(-3252 3050);
DISPLAY 0.872340 (-3252 3050);
PAINT GREEN (-3252 3050);
DISPLAY INVISIBLE (-3252 3050);
FORCEADD TAP..1
(-3250 2900);
FORCEPROP 3 LASTPIN (-3300 2900) SIG_NAME M_J_CPU1_SB_DQ<22>
J 0
(-3290 2910);
DISPLAY 0.659574 (-3290 2910);
PAINT MONO (-3290 2910);
DISPLAY INVISIBLE (-3290 2910);
FORCEPROP 1 LASTPIN (-3300 2900) BN 22
J 0
(-3312 2908);
DISPLAY 0.489362 (-3312 2908);
PAINT GREEN (-3312 2908);
FORCEPROP 2 LAST CDS_LIB mstr_standard
J 0
(-3250 2900);
DISPLAY 0.723404 (-3250 2900);
PAINT MONO (-3250 2900);
DISPLAY INVISIBLE (-3250 2900);
FORCEPROP 1 LAST BODY_TYPE PLUMBING
J 0
(-3250 2950);
DISPLAY 0.872340 (-3250 2950);
PAINT GREEN (-3250 2950);
DISPLAY INVISIBLE (-3250 2950);
FORCEPROP 1 LAST HDL_TAP TRUE
J 0
(-2925 2775);
DISPLAY 0.872340 (-2925 2775);
DISPLAY INVISIBLE (-2925 2775);
FORCEPROP 1 LAST PATH I217
J 0
(-3252 2900);
DISPLAY 0.872340 (-3252 2900);
PAINT GREEN (-3252 2900);
DISPLAY INVISIBLE (-3252 2900);
FORCEADD TAP..1
(-3250 2850);
FORCEPROP 3 LASTPIN (-3300 2850) SIG_NAME M_J_CPU1_SB_DQ<23>
J 0
(-3290 2860);
DISPLAY 0.659574 (-3290 2860);
PAINT MONO (-3290 2860);
DISPLAY INVISIBLE (-3290 2860);
FORCEPROP 1 LASTPIN (-3300 2850) BN 23
J 0
(-3312 2858);
DISPLAY 0.489362 (-3312 2858);
PAINT GREEN (-3312 2858);
FORCEPROP 2 LAST CDS_LIB mstr_standard
J 0
(-3250 2850);
DISPLAY 0.723404 (-3250 2850);
PAINT MONO (-3250 2850);
DISPLAY INVISIBLE (-3250 2850);
FORCEPROP 1 LAST BODY_TYPE PLUMBING
J 0
(-3250 2900);
DISPLAY 0.872340 (-3250 2900);
PAINT GREEN (-3250 2900);
DISPLAY INVISIBLE (-3250 2900);
FORCEPROP 1 LAST HDL_TAP TRUE
J 0
(-2925 2725);
DISPLAY 0.872340 (-2925 2725);
DISPLAY INVISIBLE (-2925 2725);
FORCEPROP 1 LAST PATH I218
J 0
(-3252 2850);
DISPLAY 0.872340 (-3252 2850);
PAINT GREEN (-3252 2850);
DISPLAY INVISIBLE (-3252 2850);
FORCEADD TAP..1
(-3250 2700);
FORCEPROP 3 LASTPIN (-3300 2700) SIG_NAME M_J_CPU1_SB_DQ<25>
J 0
(-3290 2710);
DISPLAY 0.659574 (-3290 2710);
PAINT MONO (-3290 2710);
DISPLAY INVISIBLE (-3290 2710);
FORCEPROP 1 LASTPIN (-3300 2700) BN 25
J 0
(-3312 2708);
DISPLAY 0.489362 (-3312 2708);
PAINT GREEN (-3312 2708);
FORCEPROP 2 LAST CDS_LIB mstr_standard
J 0
(-3250 2700);
DISPLAY 0.723404 (-3250 2700);
PAINT MONO (-3250 2700);
DISPLAY INVISIBLE (-3250 2700);
FORCEPROP 1 LAST BODY_TYPE PLUMBING
J 0
(-3250 2750);
DISPLAY 0.872340 (-3250 2750);
PAINT GREEN (-3250 2750);
DISPLAY INVISIBLE (-3250 2750);
FORCEPROP 1 LAST HDL_TAP TRUE
J 0
(-2925 2575);
DISPLAY 0.872340 (-2925 2575);
DISPLAY INVISIBLE (-2925 2575);
FORCEPROP 1 LAST PATH I219
J 0
(-3252 2700);
DISPLAY 0.872340 (-3252 2700);
PAINT GREEN (-3252 2700);
DISPLAY INVISIBLE (-3252 2700);
FORCEADD TAP..1
(-3250 2750);
FORCEPROP 3 LASTPIN (-3300 2750) SIG_NAME M_J_CPU1_SB_DQ<24>
J 0
(-3290 2760);
DISPLAY 0.659574 (-3290 2760);
PAINT MONO (-3290 2760);
DISPLAY INVISIBLE (-3290 2760);
FORCEPROP 1 LASTPIN (-3300 2750) BN 24
J 0
(-3312 2758);
DISPLAY 0.489362 (-3312 2758);
PAINT GREEN (-3312 2758);
FORCEPROP 2 LAST CDS_LIB mstr_standard
J 0
(-3250 2750);
DISPLAY 0.723404 (-3250 2750);
PAINT MONO (-3250 2750);
DISPLAY INVISIBLE (-3250 2750);
FORCEPROP 1 LAST BODY_TYPE PLUMBING
J 0
(-3250 2800);
DISPLAY 0.872340 (-3250 2800);
PAINT GREEN (-3250 2800);
DISPLAY INVISIBLE (-3250 2800);
FORCEPROP 1 LAST HDL_TAP TRUE
J 0
(-2925 2625);
DISPLAY 0.872340 (-2925 2625);
DISPLAY INVISIBLE (-2925 2625);
FORCEPROP 1 LAST PATH I220
J 0
(-3252 2750);
DISPLAY 0.872340 (-3252 2750);
PAINT GREEN (-3252 2750);
DISPLAY INVISIBLE (-3252 2750);
FORCEADD TAP..1
(-3250 2650);
FORCEPROP 3 LASTPIN (-3300 2650) SIG_NAME M_J_CPU1_SB_DQ<26>
J 0
(-3290 2660);
DISPLAY 0.659574 (-3290 2660);
PAINT MONO (-3290 2660);
DISPLAY INVISIBLE (-3290 2660);
FORCEPROP 1 LASTPIN (-3300 2650) BN 26
J 0
(-3312 2658);
DISPLAY 0.489362 (-3312 2658);
PAINT GREEN (-3312 2658);
FORCEPROP 2 LAST CDS_LIB mstr_standard
J 0
(-3250 2650);
DISPLAY 0.723404 (-3250 2650);
PAINT MONO (-3250 2650);
DISPLAY INVISIBLE (-3250 2650);
FORCEPROP 1 LAST BODY_TYPE PLUMBING
J 0
(-3250 2700);
DISPLAY 0.872340 (-3250 2700);
PAINT GREEN (-3250 2700);
DISPLAY INVISIBLE (-3250 2700);
FORCEPROP 1 LAST HDL_TAP TRUE
J 0
(-2925 2525);
DISPLAY 0.872340 (-2925 2525);
DISPLAY INVISIBLE (-2925 2525);
FORCEPROP 1 LAST PATH I221
J 0
(-3252 2650);
DISPLAY 0.872340 (-3252 2650);
PAINT GREEN (-3252 2650);
DISPLAY INVISIBLE (-3252 2650);
FORCEADD TAP..1
(-3250 2600);
FORCEPROP 3 LASTPIN (-3300 2600) SIG_NAME M_J_CPU1_SB_DQ<27>
J 0
(-3290 2610);
DISPLAY 0.659574 (-3290 2610);
PAINT MONO (-3290 2610);
DISPLAY INVISIBLE (-3290 2610);
FORCEPROP 1 LASTPIN (-3300 2600) BN 27
J 0
(-3312 2608);
DISPLAY 0.489362 (-3312 2608);
PAINT GREEN (-3312 2608);
FORCEPROP 2 LAST CDS_LIB mstr_standard
J 0
(-3250 2600);
DISPLAY 0.723404 (-3250 2600);
PAINT MONO (-3250 2600);
DISPLAY INVISIBLE (-3250 2600);
FORCEPROP 1 LAST BODY_TYPE PLUMBING
J 0
(-3250 2650);
DISPLAY 0.872340 (-3250 2650);
PAINT GREEN (-3250 2650);
DISPLAY INVISIBLE (-3250 2650);
FORCEPROP 1 LAST HDL_TAP TRUE
J 0
(-2925 2475);
DISPLAY 0.872340 (-2925 2475);
DISPLAY INVISIBLE (-2925 2475);
FORCEPROP 1 LAST PATH I222
J 0
(-3252 2600);
DISPLAY 0.872340 (-3252 2600);
PAINT GREEN (-3252 2600);
DISPLAY INVISIBLE (-3252 2600);
FORCEADD TAP..1
(-3250 2450);
FORCEPROP 3 LASTPIN (-3300 2450) SIG_NAME M_J_CPU1_SB_DQ<30>
J 0
(-3290 2460);
DISPLAY 0.659574 (-3290 2460);
PAINT MONO (-3290 2460);
DISPLAY INVISIBLE (-3290 2460);
FORCEPROP 1 LASTPIN (-3300 2450) BN 30
J 0
(-3312 2458);
DISPLAY 0.489362 (-3312 2458);
PAINT GREEN (-3312 2458);
FORCEPROP 2 LAST CDS_LIB mstr_standard
J 0
(-3250 2450);
DISPLAY 0.723404 (-3250 2450);
PAINT MONO (-3250 2450);
DISPLAY INVISIBLE (-3250 2450);
FORCEPROP 1 LAST BODY_TYPE PLUMBING
J 0
(-3250 2500);
DISPLAY 0.872340 (-3250 2500);
PAINT GREEN (-3250 2500);
DISPLAY INVISIBLE (-3250 2500);
FORCEPROP 1 LAST HDL_TAP TRUE
J 0
(-2925 2325);
DISPLAY 0.872340 (-2925 2325);
DISPLAY INVISIBLE (-2925 2325);
FORCEPROP 1 LAST PATH I223
J 0
(-3252 2450);
DISPLAY 0.872340 (-3252 2450);
PAINT GREEN (-3252 2450);
DISPLAY INVISIBLE (-3252 2450);
FORCEADD TAP..1
(-3250 2550);
FORCEPROP 3 LASTPIN (-3300 2550) SIG_NAME M_J_CPU1_SB_DQ<28>
J 0
(-3290 2560);
DISPLAY 0.659574 (-3290 2560);
PAINT MONO (-3290 2560);
DISPLAY INVISIBLE (-3290 2560);
FORCEPROP 1 LASTPIN (-3300 2550) BN 28
J 0
(-3312 2558);
DISPLAY 0.489362 (-3312 2558);
PAINT GREEN (-3312 2558);
FORCEPROP 2 LAST CDS_LIB mstr_standard
J 0
(-3250 2550);
DISPLAY 0.723404 (-3250 2550);
PAINT MONO (-3250 2550);
DISPLAY INVISIBLE (-3250 2550);
FORCEPROP 1 LAST BODY_TYPE PLUMBING
J 0
(-3250 2600);
DISPLAY 0.872340 (-3250 2600);
PAINT GREEN (-3250 2600);
DISPLAY INVISIBLE (-3250 2600);
FORCEPROP 1 LAST HDL_TAP TRUE
J 0
(-2925 2425);
DISPLAY 0.872340 (-2925 2425);
DISPLAY INVISIBLE (-2925 2425);
FORCEPROP 1 LAST PATH I224
J 0
(-3252 2550);
DISPLAY 0.872340 (-3252 2550);
PAINT GREEN (-3252 2550);
DISPLAY INVISIBLE (-3252 2550);
FORCEADD TAP..1
(-3250 2500);
FORCEPROP 3 LASTPIN (-3300 2500) SIG_NAME M_J_CPU1_SB_DQ<29>
J 0
(-3290 2510);
DISPLAY 0.659574 (-3290 2510);
PAINT MONO (-3290 2510);
DISPLAY INVISIBLE (-3290 2510);
FORCEPROP 1 LASTPIN (-3300 2500) BN 29
J 0
(-3312 2508);
DISPLAY 0.489362 (-3312 2508);
PAINT GREEN (-3312 2508);
FORCEPROP 2 LAST CDS_LIB mstr_standard
J 0
(-3250 2500);
DISPLAY 0.723404 (-3250 2500);
PAINT MONO (-3250 2500);
DISPLAY INVISIBLE (-3250 2500);
FORCEPROP 1 LAST BODY_TYPE PLUMBING
J 0
(-3250 2550);
DISPLAY 0.872340 (-3250 2550);
PAINT GREEN (-3250 2550);
DISPLAY INVISIBLE (-3250 2550);
FORCEPROP 1 LAST HDL_TAP TRUE
J 0
(-2925 2375);
DISPLAY 0.872340 (-2925 2375);
DISPLAY INVISIBLE (-2925 2375);
FORCEPROP 1 LAST PATH I225
J 0
(-3252 2500);
DISPLAY 0.872340 (-3252 2500);
PAINT GREEN (-3252 2500);
DISPLAY INVISIBLE (-3252 2500);
FORCEADD TAP..1
(-3250 2400);
FORCEPROP 3 LASTPIN (-3300 2400) SIG_NAME M_J_CPU1_SB_DQ<31>
J 0
(-3290 2410);
DISPLAY 0.659574 (-3290 2410);
PAINT MONO (-3290 2410);
DISPLAY INVISIBLE (-3290 2410);
FORCEPROP 1 LASTPIN (-3300 2400) BN 31
J 0
(-3312 2408);
DISPLAY 0.489362 (-3312 2408);
PAINT GREEN (-3312 2408);
FORCEPROP 2 LAST CDS_LIB mstr_standard
J 0
(-3250 2400);
DISPLAY 0.723404 (-3250 2400);
PAINT MONO (-3250 2400);
DISPLAY INVISIBLE (-3250 2400);
FORCEPROP 1 LAST BODY_TYPE PLUMBING
J 0
(-3250 2450);
DISPLAY 0.872340 (-3250 2450);
PAINT GREEN (-3250 2450);
DISPLAY INVISIBLE (-3250 2450);
FORCEPROP 1 LAST HDL_TAP TRUE
J 0
(-2925 2275);
DISPLAY 0.872340 (-2925 2275);
DISPLAY INVISIBLE (-2925 2275);
FORCEPROP 1 LAST PATH I226
J 0
(-3252 2400);
DISPLAY 0.872340 (-3252 2400);
PAINT GREEN (-3252 2400);
DISPLAY INVISIBLE (-3252 2400);
FORCEADD TAP..1
(-3250 2300);
FORCEPROP 3 LASTPIN (-3300 2300) SIG_NAME M_J_CPU1_SA_CB<0>
J 0
(-3290 2310);
DISPLAY 0.659574 (-3290 2310);
PAINT MONO (-3290 2310);
DISPLAY INVISIBLE (-3290 2310);
FORCEPROP 1 LASTPIN (-3300 2300) BN 0
J 0
(-3312 2308);
DISPLAY 0.489362 (-3312 2308);
PAINT GREEN (-3312 2308);
FORCEPROP 2 LAST CDS_LIB mstr_standard
J 2
(-3250 2300);
DISPLAY 0.723404 (-3250 2300);
PAINT MONO (-3250 2300);
DISPLAY INVISIBLE (-3250 2300);
FORCEPROP 1 LAST BODY_TYPE PLUMBING
J 0
(-3250 2350);
DISPLAY 0.872340 (-3250 2350);
PAINT GREEN (-3250 2350);
DISPLAY INVISIBLE (-3250 2350);
FORCEPROP 1 LAST HDL_TAP TRUE
J 0
(-2925 2175);
DISPLAY 0.872340 (-2925 2175);
DISPLAY INVISIBLE (-2925 2175);
FORCEPROP 1 LAST PATH I227
J 0
(-3252 2300);
DISPLAY 0.872340 (-3252 2300);
PAINT GREEN (-3252 2300);
DISPLAY INVISIBLE (-3252 2300);
FORCEADD TAP..1
(-3250 2250);
FORCEPROP 3 LASTPIN (-3300 2250) SIG_NAME M_J_CPU1_SA_CB<1>
J 0
(-3290 2260);
DISPLAY 0.659574 (-3290 2260);
PAINT MONO (-3290 2260);
DISPLAY INVISIBLE (-3290 2260);
FORCEPROP 1 LASTPIN (-3300 2250) BN 1
J 0
(-3312 2258);
DISPLAY 0.489362 (-3312 2258);
PAINT GREEN (-3312 2258);
FORCEPROP 2 LAST CDS_LIB mstr_standard
J 2
(-3250 2250);
DISPLAY 0.723404 (-3250 2250);
PAINT MONO (-3250 2250);
DISPLAY INVISIBLE (-3250 2250);
FORCEPROP 1 LAST BODY_TYPE PLUMBING
J 0
(-3250 2300);
DISPLAY 0.872340 (-3250 2300);
PAINT GREEN (-3250 2300);
DISPLAY INVISIBLE (-3250 2300);
FORCEPROP 1 LAST HDL_TAP TRUE
J 0
(-2925 2125);
DISPLAY 0.872340 (-2925 2125);
DISPLAY INVISIBLE (-2925 2125);
FORCEPROP 1 LAST PATH I228
J 0
(-3252 2250);
DISPLAY 0.872340 (-3252 2250);
PAINT GREEN (-3252 2250);
DISPLAY INVISIBLE (-3252 2250);
FORCEADD TAP..1
(-3250 2200);
FORCEPROP 3 LASTPIN (-3300 2200) SIG_NAME M_J_CPU1_SA_CB<2>
J 0
(-3290 2210);
DISPLAY 0.659574 (-3290 2210);
PAINT MONO (-3290 2210);
DISPLAY INVISIBLE (-3290 2210);
FORCEPROP 1 LASTPIN (-3300 2200) BN 2
J 0
(-3312 2208);
DISPLAY 0.489362 (-3312 2208);
PAINT GREEN (-3312 2208);
FORCEPROP 2 LAST CDS_LIB mstr_standard
J 2
(-3250 2200);
DISPLAY 0.723404 (-3250 2200);
PAINT MONO (-3250 2200);
DISPLAY INVISIBLE (-3250 2200);
FORCEPROP 1 LAST BODY_TYPE PLUMBING
J 0
(-3250 2250);
DISPLAY 0.872340 (-3250 2250);
PAINT GREEN (-3250 2250);
DISPLAY INVISIBLE (-3250 2250);
FORCEPROP 1 LAST HDL_TAP TRUE
J 0
(-2925 2075);
DISPLAY 0.872340 (-2925 2075);
DISPLAY INVISIBLE (-2925 2075);
FORCEPROP 1 LAST PATH I229
J 0
(-3252 2200);
DISPLAY 0.872340 (-3252 2200);
PAINT GREEN (-3252 2200);
DISPLAY INVISIBLE (-3252 2200);
FORCEADD TAP..1
(-3250 2150);
FORCEPROP 3 LASTPIN (-3300 2150) SIG_NAME M_J_CPU1_SA_CB<3>
J 0
(-3290 2160);
DISPLAY 0.659574 (-3290 2160);
PAINT MONO (-3290 2160);
DISPLAY INVISIBLE (-3290 2160);
FORCEPROP 1 LASTPIN (-3300 2150) BN 3
J 0
(-3312 2158);
DISPLAY 0.489362 (-3312 2158);
PAINT GREEN (-3312 2158);
FORCEPROP 2 LAST CDS_LIB mstr_standard
J 2
(-3250 2150);
DISPLAY 0.723404 (-3250 2150);
PAINT MONO (-3250 2150);
DISPLAY INVISIBLE (-3250 2150);
FORCEPROP 1 LAST BODY_TYPE PLUMBING
J 0
(-3250 2200);
DISPLAY 0.872340 (-3250 2200);
PAINT GREEN (-3250 2200);
DISPLAY INVISIBLE (-3250 2200);
FORCEPROP 1 LAST HDL_TAP TRUE
J 0
(-2925 2025);
DISPLAY 0.872340 (-2925 2025);
DISPLAY INVISIBLE (-2925 2025);
FORCEPROP 1 LAST PATH I230
J 0
(-3252 2150);
DISPLAY 0.872340 (-3252 2150);
PAINT GREEN (-3252 2150);
DISPLAY INVISIBLE (-3252 2150);
FORCEADD TAP..1
(-3250 2100);
FORCEPROP 3 LASTPIN (-3300 2100) SIG_NAME M_J_CPU1_SA_CB<4>
J 0
(-3290 2110);
DISPLAY 0.659574 (-3290 2110);
PAINT MONO (-3290 2110);
DISPLAY INVISIBLE (-3290 2110);
FORCEPROP 1 LASTPIN (-3300 2100) BN 4
J 0
(-3312 2108);
DISPLAY 0.489362 (-3312 2108);
PAINT GREEN (-3312 2108);
FORCEPROP 2 LAST CDS_LIB mstr_standard
J 2
(-3250 2100);
DISPLAY 0.723404 (-3250 2100);
PAINT MONO (-3250 2100);
DISPLAY INVISIBLE (-3250 2100);
FORCEPROP 1 LAST BODY_TYPE PLUMBING
J 0
(-3250 2150);
DISPLAY 0.872340 (-3250 2150);
PAINT GREEN (-3250 2150);
DISPLAY INVISIBLE (-3250 2150);
FORCEPROP 1 LAST HDL_TAP TRUE
J 0
(-2925 1975);
DISPLAY 0.872340 (-2925 1975);
DISPLAY INVISIBLE (-2925 1975);
FORCEPROP 1 LAST PATH I231
J 0
(-3252 2100);
DISPLAY 0.872340 (-3252 2100);
PAINT GREEN (-3252 2100);
DISPLAY INVISIBLE (-3252 2100);
FORCEADD TAP..1
(-3250 2050);
FORCEPROP 3 LASTPIN (-3300 2050) SIG_NAME M_J_CPU1_SA_CB<5>
J 0
(-3290 2060);
DISPLAY 0.659574 (-3290 2060);
PAINT MONO (-3290 2060);
DISPLAY INVISIBLE (-3290 2060);
FORCEPROP 1 LASTPIN (-3300 2050) BN 5
J 0
(-3312 2058);
DISPLAY 0.489362 (-3312 2058);
PAINT GREEN (-3312 2058);
FORCEPROP 2 LAST CDS_LIB mstr_standard
J 2
(-3250 2050);
DISPLAY 0.723404 (-3250 2050);
PAINT MONO (-3250 2050);
DISPLAY INVISIBLE (-3250 2050);
FORCEPROP 1 LAST BODY_TYPE PLUMBING
J 0
(-3250 2100);
DISPLAY 0.872340 (-3250 2100);
PAINT GREEN (-3250 2100);
DISPLAY INVISIBLE (-3250 2100);
FORCEPROP 1 LAST HDL_TAP TRUE
J 0
(-2925 1925);
DISPLAY 0.872340 (-2925 1925);
DISPLAY INVISIBLE (-2925 1925);
FORCEPROP 1 LAST PATH I232
J 0
(-3252 2050);
DISPLAY 0.872340 (-3252 2050);
PAINT GREEN (-3252 2050);
DISPLAY INVISIBLE (-3252 2050);
FORCEADD OFFPAGE..6
R 2
(-2650 1900);
FORCEPROP 2 LAST $XR0 107 
J 0
(-2436 1900);
DISPLAY 0.638298 (-2436 1900);
PAINT MONO (-2436 1900);
FORCEPROP 2 LAST CDS_LIB mstr_standard
J 2
(-2650 1900);
DISPLAY 0.723404 (-2650 1900);
PAINT MONO (-2650 1900);
DISPLAY INVISIBLE (-2650 1900);
FORCEPROP 1 LAST OFFPAGE TRUE
J 2
(-2975 1775);
DISPLAY 0.872340 (-2975 1775);
PAINT GREEN (-2975 1775);
DISPLAY INVISIBLE (-2975 1775);
FORCEPROP 1 LAST COMMENT_BODY TRUE
J 2
(-2750 1825);
DISPLAY 0.872340 (-2750 1825);
PAINT GREEN (-2750 1825);
DISPLAY INVISIBLE (-2750 1825);
FORCEPROP 2 LAST PATH I233
J 0
(-2425 1950);
DISPLAY 1.021277 (-2425 1950);
DISPLAY INVISIBLE (-2425 1950);
FORCEADD TAP..1
(-3250 1950);
FORCEPROP 3 LASTPIN (-3300 1950) SIG_NAME M_J_CPU1_SA_CB<7>
J 0
(-3290 1960);
DISPLAY 0.659574 (-3290 1960);
PAINT MONO (-3290 1960);
DISPLAY INVISIBLE (-3290 1960);
FORCEPROP 1 LASTPIN (-3300 1950) BN 7
J 0
(-3312 1958);
DISPLAY 0.489362 (-3312 1958);
PAINT GREEN (-3312 1958);
FORCEPROP 2 LAST CDS_LIB mstr_standard
J 2
(-3250 1950);
DISPLAY 0.723404 (-3250 1950);
PAINT MONO (-3250 1950);
DISPLAY INVISIBLE (-3250 1950);
FORCEPROP 1 LAST BODY_TYPE PLUMBING
J 0
(-3250 2000);
DISPLAY 0.872340 (-3250 2000);
PAINT GREEN (-3250 2000);
DISPLAY INVISIBLE (-3250 2000);
FORCEPROP 1 LAST HDL_TAP TRUE
J 0
(-2925 1825);
DISPLAY 0.872340 (-2925 1825);
DISPLAY INVISIBLE (-2925 1825);
FORCEPROP 1 LAST PATH I234
J 0
(-3252 1950);
DISPLAY 0.872340 (-3252 1950);
PAINT GREEN (-3252 1950);
DISPLAY INVISIBLE (-3252 1950);
FORCEADD TAP..1
(-3250 2000);
FORCEPROP 3 LASTPIN (-3300 2000) SIG_NAME M_J_CPU1_SA_CB<6>
J 0
(-3290 2010);
DISPLAY 0.659574 (-3290 2010);
PAINT MONO (-3290 2010);
DISPLAY INVISIBLE (-3290 2010);
FORCEPROP 1 LASTPIN (-3300 2000) BN 6
J 0
(-3312 2008);
DISPLAY 0.489362 (-3312 2008);
PAINT GREEN (-3312 2008);
FORCEPROP 2 LAST CDS_LIB mstr_standard
J 2
(-3250 2000);
DISPLAY 0.723404 (-3250 2000);
PAINT MONO (-3250 2000);
DISPLAY INVISIBLE (-3250 2000);
FORCEPROP 1 LAST BODY_TYPE PLUMBING
J 0
(-3250 2050);
DISPLAY 0.872340 (-3250 2050);
PAINT GREEN (-3250 2050);
DISPLAY INVISIBLE (-3250 2050);
FORCEPROP 1 LAST HDL_TAP TRUE
J 0
(-2925 1875);
DISPLAY 0.872340 (-2925 1875);
DISPLAY INVISIBLE (-2925 1875);
FORCEPROP 1 LAST PATH I235
J 0
(-3252 2000);
DISPLAY 0.872340 (-3252 2000);
PAINT GREEN (-3252 2000);
DISPLAY INVISIBLE (-3252 2000);
FORCEADD TAP..1
(-3250 1800);
FORCEPROP 3 LASTPIN (-3300 1800) SIG_NAME M_J_CPU1_SB_CB<1>
J 0
(-3290 1810);
DISPLAY 0.659574 (-3290 1810);
PAINT MONO (-3290 1810);
DISPLAY INVISIBLE (-3290 1810);
FORCEPROP 1 LASTPIN (-3300 1800) BN 1
J 0
(-3312 1808);
DISPLAY 0.489362 (-3312 1808);
PAINT GREEN (-3312 1808);
FORCEPROP 2 LAST CDS_LIB mstr_standard
J 2
(-3250 1800);
DISPLAY 0.723404 (-3250 1800);
PAINT MONO (-3250 1800);
DISPLAY INVISIBLE (-3250 1800);
FORCEPROP 1 LAST BODY_TYPE PLUMBING
J 0
(-3250 1850);
DISPLAY 0.872340 (-3250 1850);
PAINT GREEN (-3250 1850);
DISPLAY INVISIBLE (-3250 1850);
FORCEPROP 1 LAST HDL_TAP TRUE
J 0
(-2925 1675);
DISPLAY 0.872340 (-2925 1675);
DISPLAY INVISIBLE (-2925 1675);
FORCEPROP 1 LAST PATH I236
J 0
(-3252 1800);
DISPLAY 0.872340 (-3252 1800);
PAINT GREEN (-3252 1800);
DISPLAY INVISIBLE (-3252 1800);
FORCEADD TAP..1
(-3250 1850);
FORCEPROP 3 LASTPIN (-3300 1850) SIG_NAME M_J_CPU1_SB_CB<0>
J 0
(-3290 1860);
DISPLAY 0.659574 (-3290 1860);
PAINT MONO (-3290 1860);
DISPLAY INVISIBLE (-3290 1860);
FORCEPROP 1 LASTPIN (-3300 1850) BN 0
J 0
(-3312 1858);
DISPLAY 0.489362 (-3312 1858);
PAINT GREEN (-3312 1858);
FORCEPROP 2 LAST CDS_LIB mstr_standard
J 2
(-3250 1850);
DISPLAY 0.723404 (-3250 1850);
PAINT MONO (-3250 1850);
DISPLAY INVISIBLE (-3250 1850);
FORCEPROP 1 LAST BODY_TYPE PLUMBING
J 0
(-3250 1900);
DISPLAY 0.872340 (-3250 1900);
PAINT GREEN (-3250 1900);
DISPLAY INVISIBLE (-3250 1900);
FORCEPROP 1 LAST HDL_TAP TRUE
J 0
(-2925 1725);
DISPLAY 0.872340 (-2925 1725);
DISPLAY INVISIBLE (-2925 1725);
FORCEPROP 1 LAST PATH I237
J 0
(-3252 1850);
DISPLAY 0.872340 (-3252 1850);
PAINT GREEN (-3252 1850);
DISPLAY INVISIBLE (-3252 1850);
FORCEADD TAP..1
(-3250 1700);
FORCEPROP 3 LASTPIN (-3300 1700) SIG_NAME M_J_CPU1_SB_CB<3>
J 0
(-3290 1710);
DISPLAY 0.659574 (-3290 1710);
PAINT MONO (-3290 1710);
DISPLAY INVISIBLE (-3290 1710);
FORCEPROP 1 LASTPIN (-3300 1700) BN 3
J 0
(-3312 1708);
DISPLAY 0.489362 (-3312 1708);
PAINT GREEN (-3312 1708);
FORCEPROP 2 LAST CDS_LIB mstr_standard
J 2
(-3250 1700);
DISPLAY 0.723404 (-3250 1700);
PAINT MONO (-3250 1700);
DISPLAY INVISIBLE (-3250 1700);
FORCEPROP 1 LAST BODY_TYPE PLUMBING
J 0
(-3250 1750);
DISPLAY 0.872340 (-3250 1750);
PAINT GREEN (-3250 1750);
DISPLAY INVISIBLE (-3250 1750);
FORCEPROP 1 LAST HDL_TAP TRUE
J 0
(-2925 1575);
DISPLAY 0.872340 (-2925 1575);
DISPLAY INVISIBLE (-2925 1575);
FORCEPROP 1 LAST PATH I238
J 0
(-3252 1700);
DISPLAY 0.872340 (-3252 1700);
PAINT GREEN (-3252 1700);
DISPLAY INVISIBLE (-3252 1700);
FORCEADD TAP..1
(-3250 1750);
FORCEPROP 3 LASTPIN (-3300 1750) SIG_NAME M_J_CPU1_SB_CB<2>
J 0
(-3290 1760);
DISPLAY 0.659574 (-3290 1760);
PAINT MONO (-3290 1760);
DISPLAY INVISIBLE (-3290 1760);
FORCEPROP 1 LASTPIN (-3300 1750) BN 2
J 0
(-3312 1758);
DISPLAY 0.489362 (-3312 1758);
PAINT GREEN (-3312 1758);
FORCEPROP 2 LAST CDS_LIB mstr_standard
J 2
(-3250 1750);
DISPLAY 0.723404 (-3250 1750);
PAINT MONO (-3250 1750);
DISPLAY INVISIBLE (-3250 1750);
FORCEPROP 1 LAST BODY_TYPE PLUMBING
J 0
(-3250 1800);
DISPLAY 0.872340 (-3250 1800);
PAINT GREEN (-3250 1800);
DISPLAY INVISIBLE (-3250 1800);
FORCEPROP 1 LAST HDL_TAP TRUE
J 0
(-2925 1625);
DISPLAY 0.872340 (-2925 1625);
DISPLAY INVISIBLE (-2925 1625);
FORCEPROP 1 LAST PATH I239
J 0
(-3252 1750);
DISPLAY 0.872340 (-3252 1750);
PAINT GREEN (-3252 1750);
DISPLAY INVISIBLE (-3252 1750);
FORCEADD TAP..1
(-3250 1650);
FORCEPROP 3 LASTPIN (-3300 1650) SIG_NAME M_J_CPU1_SB_CB<4>
J 0
(-3290 1660);
DISPLAY 0.659574 (-3290 1660);
PAINT MONO (-3290 1660);
DISPLAY INVISIBLE (-3290 1660);
FORCEPROP 1 LASTPIN (-3300 1650) BN 4
J 0
(-3312 1658);
DISPLAY 0.489362 (-3312 1658);
PAINT GREEN (-3312 1658);
FORCEPROP 2 LAST CDS_LIB mstr_standard
J 2
(-3250 1650);
DISPLAY 0.723404 (-3250 1650);
PAINT MONO (-3250 1650);
DISPLAY INVISIBLE (-3250 1650);
FORCEPROP 1 LAST BODY_TYPE PLUMBING
J 0
(-3250 1700);
DISPLAY 0.872340 (-3250 1700);
PAINT GREEN (-3250 1700);
DISPLAY INVISIBLE (-3250 1700);
FORCEPROP 1 LAST HDL_TAP TRUE
J 0
(-2925 1525);
DISPLAY 0.872340 (-2925 1525);
DISPLAY INVISIBLE (-2925 1525);
FORCEPROP 1 LAST PATH I240
J 0
(-3252 1650);
DISPLAY 0.872340 (-3252 1650);
PAINT GREEN (-3252 1650);
DISPLAY INVISIBLE (-3252 1650);
FORCEADD TAP..1
(-3250 1600);
FORCEPROP 3 LASTPIN (-3300 1600) SIG_NAME M_J_CPU1_SB_CB<5>
J 0
(-3290 1610);
DISPLAY 0.659574 (-3290 1610);
PAINT MONO (-3290 1610);
DISPLAY INVISIBLE (-3290 1610);
FORCEPROP 1 LASTPIN (-3300 1600) BN 5
J 0
(-3312 1608);
DISPLAY 0.489362 (-3312 1608);
PAINT GREEN (-3312 1608);
FORCEPROP 2 LAST CDS_LIB mstr_standard
J 2
(-3250 1600);
DISPLAY 0.723404 (-3250 1600);
PAINT MONO (-3250 1600);
DISPLAY INVISIBLE (-3250 1600);
FORCEPROP 1 LAST BODY_TYPE PLUMBING
J 0
(-3250 1650);
DISPLAY 0.872340 (-3250 1650);
PAINT GREEN (-3250 1650);
DISPLAY INVISIBLE (-3250 1650);
FORCEPROP 1 LAST HDL_TAP TRUE
J 0
(-2925 1475);
DISPLAY 0.872340 (-2925 1475);
DISPLAY INVISIBLE (-2925 1475);
FORCEPROP 1 LAST PATH I241
J 0
(-3252 1600);
DISPLAY 0.872340 (-3252 1600);
PAINT GREEN (-3252 1600);
DISPLAY INVISIBLE (-3252 1600);
FORCEADD TAP..1
(-3250 1550);
FORCEPROP 3 LASTPIN (-3300 1550) SIG_NAME M_J_CPU1_SB_CB<6>
J 0
(-3290 1560);
DISPLAY 0.659574 (-3290 1560);
PAINT MONO (-3290 1560);
DISPLAY INVISIBLE (-3290 1560);
FORCEPROP 1 LASTPIN (-3300 1550) BN 6
J 0
(-3312 1558);
DISPLAY 0.489362 (-3312 1558);
PAINT GREEN (-3312 1558);
FORCEPROP 2 LAST CDS_LIB mstr_standard
J 2
(-3250 1550);
DISPLAY 0.723404 (-3250 1550);
PAINT MONO (-3250 1550);
DISPLAY INVISIBLE (-3250 1550);
FORCEPROP 1 LAST BODY_TYPE PLUMBING
J 0
(-3250 1600);
DISPLAY 0.872340 (-3250 1600);
PAINT GREEN (-3250 1600);
DISPLAY INVISIBLE (-3250 1600);
FORCEPROP 1 LAST HDL_TAP TRUE
J 0
(-2925 1425);
DISPLAY 0.872340 (-2925 1425);
DISPLAY INVISIBLE (-2925 1425);
FORCEPROP 1 LAST PATH I242
J 0
(-3252 1550);
DISPLAY 0.872340 (-3252 1550);
PAINT GREEN (-3252 1550);
DISPLAY INVISIBLE (-3252 1550);
FORCEADD TAP..1
(-3250 1500);
FORCEPROP 3 LASTPIN (-3300 1500) SIG_NAME M_J_CPU1_SB_CB<7>
J 0
(-3290 1510);
DISPLAY 0.659574 (-3290 1510);
PAINT MONO (-3290 1510);
DISPLAY INVISIBLE (-3290 1510);
FORCEPROP 1 LASTPIN (-3300 1500) BN 7
J 0
(-3312 1508);
DISPLAY 0.489362 (-3312 1508);
PAINT GREEN (-3312 1508);
FORCEPROP 2 LAST CDS_LIB mstr_standard
J 2
(-3250 1500);
DISPLAY 0.723404 (-3250 1500);
PAINT MONO (-3250 1500);
DISPLAY INVISIBLE (-3250 1500);
FORCEPROP 1 LAST BODY_TYPE PLUMBING
J 0
(-3250 1550);
DISPLAY 0.872340 (-3250 1550);
PAINT GREEN (-3250 1550);
DISPLAY INVISIBLE (-3250 1550);
FORCEPROP 1 LAST HDL_TAP TRUE
J 0
(-2925 1375);
DISPLAY 0.872340 (-2925 1375);
DISPLAY INVISIBLE (-2925 1375);
FORCEPROP 1 LAST PATH I243
J 0
(-3252 1500);
DISPLAY 0.872340 (-3252 1500);
PAINT GREEN (-3252 1500);
DISPLAY INVISIBLE (-3252 1500);
FORCEADD TAP..1
R 2
(-5675 5900);
FORCEPROP 3 LASTPIN (-5625 5900) SIG_NAME M_J_CPU1_SA_DQS_DP<0>
J 0
(-5615 5910);
DISPLAY 0.659574 (-5615 5910);
PAINT MONO (-5615 5910);
DISPLAY INVISIBLE (-5615 5910);
FORCEPROP 1 LASTPIN (-5625 5900) BN 0
J 2
(-5613 5908);
DISPLAY 0.489362 (-5613 5908);
PAINT GREEN (-5613 5908);
FORCEPROP 2 LAST CDS_LIB mstr_standard
J 2
(-5675 5900);
DISPLAY 0.723404 (-5675 5900);
PAINT MONO (-5675 5900);
DISPLAY INVISIBLE (-5675 5900);
FORCEPROP 1 LAST BODY_TYPE PLUMBING
J 2
(-5675 5950);
DISPLAY 0.872340 (-5675 5950);
PAINT GREEN (-5675 5950);
DISPLAY INVISIBLE (-5675 5950);
FORCEPROP 1 LAST HDL_TAP TRUE
J 2
(-6000 5775);
DISPLAY 0.872340 (-6000 5775);
DISPLAY INVISIBLE (-6000 5775);
FORCEPROP 1 LAST PATH I244
J 2
(-5673 5900);
DISPLAY 0.872340 (-5673 5900);
PAINT GREEN (-5673 5900);
DISPLAY INVISIBLE (-5673 5900);
FORCEADD TAP..1
R 2
(-5675 5800);
FORCEPROP 3 LASTPIN (-5625 5800) SIG_NAME M_J_CPU1_SA_DQS_DP<1>
J 0
(-5615 5810);
DISPLAY 0.659574 (-5615 5810);
PAINT MONO (-5615 5810);
DISPLAY INVISIBLE (-5615 5810);
FORCEPROP 1 LASTPIN (-5625 5800) BN 1
J 2
(-5613 5808);
DISPLAY 0.489362 (-5613 5808);
PAINT GREEN (-5613 5808);
FORCEPROP 2 LAST CDS_LIB mstr_standard
J 2
(-5675 5800);
DISPLAY 0.723404 (-5675 5800);
PAINT MONO (-5675 5800);
DISPLAY INVISIBLE (-5675 5800);
FORCEPROP 1 LAST BODY_TYPE PLUMBING
J 2
(-5675 5850);
DISPLAY 0.872340 (-5675 5850);
PAINT GREEN (-5675 5850);
DISPLAY INVISIBLE (-5675 5850);
FORCEPROP 1 LAST HDL_TAP TRUE
J 2
(-6000 5675);
DISPLAY 0.872340 (-6000 5675);
DISPLAY INVISIBLE (-6000 5675);
FORCEPROP 1 LAST PATH I245
J 2
(-5673 5800);
DISPLAY 0.872340 (-5673 5800);
PAINT GREEN (-5673 5800);
DISPLAY INVISIBLE (-5673 5800);
FORCEADD TAP..1
R 2
(-5675 5700);
FORCEPROP 3 LASTPIN (-5625 5700) SIG_NAME M_J_CPU1_SA_DQS_DP<2>
J 0
(-5615 5710);
DISPLAY 0.659574 (-5615 5710);
PAINT MONO (-5615 5710);
DISPLAY INVISIBLE (-5615 5710);
FORCEPROP 1 LASTPIN (-5625 5700) BN 2
J 2
(-5613 5708);
DISPLAY 0.489362 (-5613 5708);
PAINT GREEN (-5613 5708);
FORCEPROP 2 LAST CDS_LIB mstr_standard
J 2
(-5675 5700);
DISPLAY 0.723404 (-5675 5700);
PAINT MONO (-5675 5700);
DISPLAY INVISIBLE (-5675 5700);
FORCEPROP 1 LAST BODY_TYPE PLUMBING
J 2
(-5675 5750);
DISPLAY 0.872340 (-5675 5750);
PAINT GREEN (-5675 5750);
DISPLAY INVISIBLE (-5675 5750);
FORCEPROP 1 LAST HDL_TAP TRUE
J 2
(-6000 5575);
DISPLAY 0.872340 (-6000 5575);
DISPLAY INVISIBLE (-6000 5575);
FORCEPROP 1 LAST PATH I246
J 2
(-5673 5700);
DISPLAY 0.872340 (-5673 5700);
PAINT GREEN (-5673 5700);
DISPLAY INVISIBLE (-5673 5700);
FORCEADD TAP..1
R 2
(-5675 5600);
FORCEPROP 3 LASTPIN (-5625 5600) SIG_NAME M_J_CPU1_SA_DQS_DP<3>
J 0
(-5615 5610);
DISPLAY 0.659574 (-5615 5610);
PAINT MONO (-5615 5610);
DISPLAY INVISIBLE (-5615 5610);
FORCEPROP 1 LASTPIN (-5625 5600) BN 3
J 2
(-5613 5608);
DISPLAY 0.489362 (-5613 5608);
PAINT GREEN (-5613 5608);
FORCEPROP 2 LAST CDS_LIB mstr_standard
J 2
(-5675 5600);
DISPLAY 0.723404 (-5675 5600);
PAINT MONO (-5675 5600);
DISPLAY INVISIBLE (-5675 5600);
FORCEPROP 1 LAST BODY_TYPE PLUMBING
J 2
(-5675 5650);
DISPLAY 0.872340 (-5675 5650);
PAINT GREEN (-5675 5650);
DISPLAY INVISIBLE (-5675 5650);
FORCEPROP 1 LAST HDL_TAP TRUE
J 2
(-6000 5475);
DISPLAY 0.872340 (-6000 5475);
DISPLAY INVISIBLE (-6000 5475);
FORCEPROP 1 LAST PATH I247
J 2
(-5673 5600);
DISPLAY 0.872340 (-5673 5600);
PAINT GREEN (-5673 5600);
DISPLAY INVISIBLE (-5673 5600);
FORCEADD TAP..1
R 2
(-5675 5500);
FORCEPROP 3 LASTPIN (-5625 5500) SIG_NAME M_J_CPU1_SA_DQS_DP<4>
J 0
(-5615 5510);
DISPLAY 0.659574 (-5615 5510);
PAINT MONO (-5615 5510);
DISPLAY INVISIBLE (-5615 5510);
FORCEPROP 1 LASTPIN (-5625 5500) BN 4
J 2
(-5613 5508);
DISPLAY 0.489362 (-5613 5508);
PAINT GREEN (-5613 5508);
FORCEPROP 2 LAST CDS_LIB mstr_standard
J 2
(-5675 5500);
DISPLAY 0.723404 (-5675 5500);
PAINT MONO (-5675 5500);
DISPLAY INVISIBLE (-5675 5500);
FORCEPROP 1 LAST BODY_TYPE PLUMBING
J 2
(-5675 5550);
DISPLAY 0.872340 (-5675 5550);
PAINT GREEN (-5675 5550);
DISPLAY INVISIBLE (-5675 5550);
FORCEPROP 1 LAST HDL_TAP TRUE
J 2
(-6000 5375);
DISPLAY 0.872340 (-6000 5375);
DISPLAY INVISIBLE (-6000 5375);
FORCEPROP 1 LAST PATH I248
J 2
(-5673 5500);
DISPLAY 0.872340 (-5673 5500);
PAINT GREEN (-5673 5500);
DISPLAY INVISIBLE (-5673 5500);
FORCEADD TAP..1
R 2
(-5675 5400);
FORCEPROP 3 LASTPIN (-5625 5400) SIG_NAME M_J_CPU1_SA_DQS_DP<5>
J 0
(-5615 5410);
DISPLAY 0.659574 (-5615 5410);
PAINT MONO (-5615 5410);
DISPLAY INVISIBLE (-5615 5410);
FORCEPROP 1 LASTPIN (-5625 5400) BN 5
J 2
(-5613 5408);
DISPLAY 0.489362 (-5613 5408);
PAINT GREEN (-5613 5408);
FORCEPROP 2 LAST CDS_LIB mstr_standard
J 2
(-5675 5400);
DISPLAY 0.723404 (-5675 5400);
PAINT MONO (-5675 5400);
DISPLAY INVISIBLE (-5675 5400);
FORCEPROP 1 LAST BODY_TYPE PLUMBING
J 2
(-5675 5450);
DISPLAY 0.872340 (-5675 5450);
PAINT GREEN (-5675 5450);
DISPLAY INVISIBLE (-5675 5450);
FORCEPROP 1 LAST HDL_TAP TRUE
J 2
(-6000 5275);
DISPLAY 0.872340 (-6000 5275);
DISPLAY INVISIBLE (-6000 5275);
FORCEPROP 1 LAST PATH I249
J 2
(-5673 5400);
DISPLAY 0.872340 (-5673 5400);
PAINT GREEN (-5673 5400);
DISPLAY INVISIBLE (-5673 5400);
FORCEADD TAP..1
R 2
(-5675 5300);
FORCEPROP 3 LASTPIN (-5625 5300) SIG_NAME M_J_CPU1_SA_DQS_DP<6>
J 0
(-5615 5310);
DISPLAY 0.659574 (-5615 5310);
PAINT MONO (-5615 5310);
DISPLAY INVISIBLE (-5615 5310);
FORCEPROP 1 LASTPIN (-5625 5300) BN 6
J 2
(-5613 5308);
DISPLAY 0.489362 (-5613 5308);
PAINT GREEN (-5613 5308);
FORCEPROP 2 LAST CDS_LIB mstr_standard
J 2
(-5675 5300);
DISPLAY 0.723404 (-5675 5300);
PAINT MONO (-5675 5300);
DISPLAY INVISIBLE (-5675 5300);
FORCEPROP 1 LAST BODY_TYPE PLUMBING
J 2
(-5675 5350);
DISPLAY 0.872340 (-5675 5350);
PAINT GREEN (-5675 5350);
DISPLAY INVISIBLE (-5675 5350);
FORCEPROP 1 LAST HDL_TAP TRUE
J 2
(-6000 5175);
DISPLAY 0.872340 (-6000 5175);
DISPLAY INVISIBLE (-6000 5175);
FORCEPROP 1 LAST PATH I250
J 2
(-5673 5300);
DISPLAY 0.872340 (-5673 5300);
PAINT GREEN (-5673 5300);
DISPLAY INVISIBLE (-5673 5300);
FORCEADD TAP..1
R 2
(-5675 5200);
FORCEPROP 3 LASTPIN (-5625 5200) SIG_NAME M_J_CPU1_SA_DQS_DP<7>
J 0
(-5615 5210);
DISPLAY 0.659574 (-5615 5210);
PAINT MONO (-5615 5210);
DISPLAY INVISIBLE (-5615 5210);
FORCEPROP 1 LASTPIN (-5625 5200) BN 7
J 2
(-5613 5208);
DISPLAY 0.489362 (-5613 5208);
PAINT GREEN (-5613 5208);
FORCEPROP 2 LAST CDS_LIB mstr_standard
J 2
(-5675 5200);
DISPLAY 0.723404 (-5675 5200);
PAINT MONO (-5675 5200);
DISPLAY INVISIBLE (-5675 5200);
FORCEPROP 1 LAST BODY_TYPE PLUMBING
J 2
(-5675 5250);
DISPLAY 0.872340 (-5675 5250);
PAINT GREEN (-5675 5250);
DISPLAY INVISIBLE (-5675 5250);
FORCEPROP 1 LAST HDL_TAP TRUE
J 2
(-6000 5075);
DISPLAY 0.872340 (-6000 5075);
DISPLAY INVISIBLE (-6000 5075);
FORCEPROP 1 LAST PATH I251
J 2
(-5673 5200);
DISPLAY 0.872340 (-5673 5200);
PAINT GREEN (-5673 5200);
DISPLAY INVISIBLE (-5673 5200);
FORCEADD TAP..1
R 2
(-5875 5850);
FORCEPROP 3 LASTPIN (-5825 5850) SIG_NAME M_J_CPU1_SA_DQS_DN<0>
J 0
(-5815 5860);
DISPLAY 0.659574 (-5815 5860);
PAINT MONO (-5815 5860);
DISPLAY INVISIBLE (-5815 5860);
FORCEPROP 1 LASTPIN (-5825 5850) BN 0
J 2
(-5813 5858);
DISPLAY 0.489362 (-5813 5858);
PAINT GREEN (-5813 5858);
FORCEPROP 2 LAST CDS_LIB mstr_standard
J 2
(-5875 5850);
DISPLAY 0.723404 (-5875 5850);
PAINT MONO (-5875 5850);
DISPLAY INVISIBLE (-5875 5850);
FORCEPROP 1 LAST BODY_TYPE PLUMBING
J 2
(-5875 5900);
DISPLAY 0.872340 (-5875 5900);
PAINT GREEN (-5875 5900);
DISPLAY INVISIBLE (-5875 5900);
FORCEPROP 1 LAST HDL_TAP TRUE
J 2
(-6200 5725);
DISPLAY 0.872340 (-6200 5725);
DISPLAY INVISIBLE (-6200 5725);
FORCEPROP 1 LAST PATH I252
J 2
(-5873 5850);
DISPLAY 0.872340 (-5873 5850);
PAINT GREEN (-5873 5850);
DISPLAY INVISIBLE (-5873 5850);
FORCEADD TAP..1
R 2
(-5875 5650);
FORCEPROP 3 LASTPIN (-5825 5650) SIG_NAME M_J_CPU1_SA_DQS_DN<2>
J 0
(-5815 5660);
DISPLAY 0.659574 (-5815 5660);
PAINT MONO (-5815 5660);
DISPLAY INVISIBLE (-5815 5660);
FORCEPROP 1 LASTPIN (-5825 5650) BN 2
J 2
(-5813 5658);
DISPLAY 0.489362 (-5813 5658);
PAINT GREEN (-5813 5658);
FORCEPROP 2 LAST CDS_LIB mstr_standard
J 2
(-5875 5650);
DISPLAY 0.723404 (-5875 5650);
PAINT MONO (-5875 5650);
DISPLAY INVISIBLE (-5875 5650);
FORCEPROP 1 LAST BODY_TYPE PLUMBING
J 2
(-5875 5700);
DISPLAY 0.872340 (-5875 5700);
PAINT GREEN (-5875 5700);
DISPLAY INVISIBLE (-5875 5700);
FORCEPROP 1 LAST HDL_TAP TRUE
J 2
(-6200 5525);
DISPLAY 0.872340 (-6200 5525);
DISPLAY INVISIBLE (-6200 5525);
FORCEPROP 1 LAST PATH I253
J 2
(-5873 5650);
DISPLAY 0.872340 (-5873 5650);
PAINT GREEN (-5873 5650);
DISPLAY INVISIBLE (-5873 5650);
FORCEADD TAP..1
R 2
(-5875 5750);
FORCEPROP 3 LASTPIN (-5825 5750) SIG_NAME M_J_CPU1_SA_DQS_DN<1>
J 0
(-5815 5760);
DISPLAY 0.659574 (-5815 5760);
PAINT MONO (-5815 5760);
DISPLAY INVISIBLE (-5815 5760);
FORCEPROP 1 LASTPIN (-5825 5750) BN 1
J 2
(-5813 5758);
DISPLAY 0.489362 (-5813 5758);
PAINT GREEN (-5813 5758);
FORCEPROP 2 LAST CDS_LIB mstr_standard
J 2
(-5875 5750);
DISPLAY 0.723404 (-5875 5750);
PAINT MONO (-5875 5750);
DISPLAY INVISIBLE (-5875 5750);
FORCEPROP 1 LAST BODY_TYPE PLUMBING
J 2
(-5875 5800);
DISPLAY 0.872340 (-5875 5800);
PAINT GREEN (-5875 5800);
DISPLAY INVISIBLE (-5875 5800);
FORCEPROP 1 LAST HDL_TAP TRUE
J 2
(-6200 5625);
DISPLAY 0.872340 (-6200 5625);
DISPLAY INVISIBLE (-6200 5625);
FORCEPROP 1 LAST PATH I254
J 2
(-5873 5750);
DISPLAY 0.872340 (-5873 5750);
PAINT GREEN (-5873 5750);
DISPLAY INVISIBLE (-5873 5750);
FORCEADD TAP..1
R 2
(-5875 5550);
FORCEPROP 3 LASTPIN (-5825 5550) SIG_NAME M_J_CPU1_SA_DQS_DN<3>
J 0
(-5815 5560);
DISPLAY 0.659574 (-5815 5560);
PAINT MONO (-5815 5560);
DISPLAY INVISIBLE (-5815 5560);
FORCEPROP 1 LASTPIN (-5825 5550) BN 3
J 2
(-5813 5558);
DISPLAY 0.489362 (-5813 5558);
PAINT GREEN (-5813 5558);
FORCEPROP 2 LAST CDS_LIB mstr_standard
J 2
(-5875 5550);
DISPLAY 0.723404 (-5875 5550);
PAINT MONO (-5875 5550);
DISPLAY INVISIBLE (-5875 5550);
FORCEPROP 1 LAST BODY_TYPE PLUMBING
J 2
(-5875 5600);
DISPLAY 0.872340 (-5875 5600);
PAINT GREEN (-5875 5600);
DISPLAY INVISIBLE (-5875 5600);
FORCEPROP 1 LAST HDL_TAP TRUE
J 2
(-6200 5425);
DISPLAY 0.872340 (-6200 5425);
DISPLAY INVISIBLE (-6200 5425);
FORCEPROP 1 LAST PATH I255
J 2
(-5873 5550);
DISPLAY 0.872340 (-5873 5550);
PAINT GREEN (-5873 5550);
DISPLAY INVISIBLE (-5873 5550);
FORCEADD TAP..1
R 2
(-5875 5450);
FORCEPROP 3 LASTPIN (-5825 5450) SIG_NAME M_J_CPU1_SA_DQS_DN<4>
J 0
(-5815 5460);
DISPLAY 0.659574 (-5815 5460);
PAINT MONO (-5815 5460);
DISPLAY INVISIBLE (-5815 5460);
FORCEPROP 1 LASTPIN (-5825 5450) BN 4
J 2
(-5813 5458);
DISPLAY 0.489362 (-5813 5458);
PAINT GREEN (-5813 5458);
FORCEPROP 2 LAST CDS_LIB mstr_standard
J 2
(-5875 5450);
DISPLAY 0.723404 (-5875 5450);
PAINT MONO (-5875 5450);
DISPLAY INVISIBLE (-5875 5450);
FORCEPROP 1 LAST BODY_TYPE PLUMBING
J 2
(-5875 5500);
DISPLAY 0.872340 (-5875 5500);
PAINT GREEN (-5875 5500);
DISPLAY INVISIBLE (-5875 5500);
FORCEPROP 1 LAST HDL_TAP TRUE
J 2
(-6200 5325);
DISPLAY 0.872340 (-6200 5325);
DISPLAY INVISIBLE (-6200 5325);
FORCEPROP 1 LAST PATH I256
J 2
(-5873 5450);
DISPLAY 0.872340 (-5873 5450);
PAINT GREEN (-5873 5450);
DISPLAY INVISIBLE (-5873 5450);
FORCEADD TAP..1
R 2
(-5875 5250);
FORCEPROP 3 LASTPIN (-5825 5250) SIG_NAME M_J_CPU1_SA_DQS_DN<6>
J 0
(-5815 5260);
DISPLAY 0.659574 (-5815 5260);
PAINT MONO (-5815 5260);
DISPLAY INVISIBLE (-5815 5260);
FORCEPROP 1 LASTPIN (-5825 5250) BN 6
J 2
(-5813 5258);
DISPLAY 0.489362 (-5813 5258);
PAINT GREEN (-5813 5258);
FORCEPROP 2 LAST CDS_LIB mstr_standard
J 2
(-5875 5250);
DISPLAY 0.723404 (-5875 5250);
PAINT MONO (-5875 5250);
DISPLAY INVISIBLE (-5875 5250);
FORCEPROP 1 LAST BODY_TYPE PLUMBING
J 2
(-5875 5300);
DISPLAY 0.872340 (-5875 5300);
PAINT GREEN (-5875 5300);
DISPLAY INVISIBLE (-5875 5300);
FORCEPROP 1 LAST HDL_TAP TRUE
J 2
(-6200 5125);
DISPLAY 0.872340 (-6200 5125);
DISPLAY INVISIBLE (-6200 5125);
FORCEPROP 1 LAST PATH I257
J 2
(-5873 5250);
DISPLAY 0.872340 (-5873 5250);
PAINT GREEN (-5873 5250);
DISPLAY INVISIBLE (-5873 5250);
FORCEADD TAP..1
R 2
(-5875 5350);
FORCEPROP 3 LASTPIN (-5825 5350) SIG_NAME M_J_CPU1_SA_DQS_DN<5>
J 0
(-5815 5360);
DISPLAY 0.659574 (-5815 5360);
PAINT MONO (-5815 5360);
DISPLAY INVISIBLE (-5815 5360);
FORCEPROP 1 LASTPIN (-5825 5350) BN 5
J 2
(-5813 5358);
DISPLAY 0.489362 (-5813 5358);
PAINT GREEN (-5813 5358);
FORCEPROP 2 LAST CDS_LIB mstr_standard
J 2
(-5875 5350);
DISPLAY 0.723404 (-5875 5350);
PAINT MONO (-5875 5350);
DISPLAY INVISIBLE (-5875 5350);
FORCEPROP 1 LAST BODY_TYPE PLUMBING
J 2
(-5875 5400);
DISPLAY 0.872340 (-5875 5400);
PAINT GREEN (-5875 5400);
DISPLAY INVISIBLE (-5875 5400);
FORCEPROP 1 LAST HDL_TAP TRUE
J 2
(-6200 5225);
DISPLAY 0.872340 (-6200 5225);
DISPLAY INVISIBLE (-6200 5225);
FORCEPROP 1 LAST PATH I258
J 2
(-5873 5350);
DISPLAY 0.872340 (-5873 5350);
PAINT GREEN (-5873 5350);
DISPLAY INVISIBLE (-5873 5350);
FORCEADD TAP..1
R 2
(-5875 5150);
FORCEPROP 3 LASTPIN (-5825 5150) SIG_NAME M_J_CPU1_SA_DQS_DN<7>
J 0
(-5815 5160);
DISPLAY 0.659574 (-5815 5160);
PAINT MONO (-5815 5160);
DISPLAY INVISIBLE (-5815 5160);
FORCEPROP 1 LASTPIN (-5825 5150) BN 7
J 2
(-5813 5158);
DISPLAY 0.489362 (-5813 5158);
PAINT GREEN (-5813 5158);
FORCEPROP 2 LAST CDS_LIB mstr_standard
J 2
(-5875 5150);
DISPLAY 0.723404 (-5875 5150);
PAINT MONO (-5875 5150);
DISPLAY INVISIBLE (-5875 5150);
FORCEPROP 1 LAST BODY_TYPE PLUMBING
J 2
(-5875 5200);
DISPLAY 0.872340 (-5875 5200);
PAINT GREEN (-5875 5200);
DISPLAY INVISIBLE (-5875 5200);
FORCEPROP 1 LAST HDL_TAP TRUE
J 2
(-6200 5025);
DISPLAY 0.872340 (-6200 5025);
DISPLAY INVISIBLE (-6200 5025);
FORCEPROP 1 LAST PATH I259
J 2
(-5873 5150);
DISPLAY 0.872340 (-5873 5150);
PAINT GREEN (-5873 5150);
DISPLAY INVISIBLE (-5873 5150);
FORCEADD TAP..1
R 2
(-5675 5000);
FORCEPROP 3 LASTPIN (-5625 5000) SIG_NAME M_J_CPU1_SA_DQS_DP<9>
J 0
(-5615 5010);
DISPLAY 0.659574 (-5615 5010);
PAINT MONO (-5615 5010);
DISPLAY INVISIBLE (-5615 5010);
FORCEPROP 1 LASTPIN (-5625 5000) BN 9
J 2
(-5613 5008);
DISPLAY 0.489362 (-5613 5008);
PAINT GREEN (-5613 5008);
FORCEPROP 2 LAST CDS_LIB mstr_standard
J 2
(-5675 5000);
DISPLAY 0.723404 (-5675 5000);
PAINT MONO (-5675 5000);
DISPLAY INVISIBLE (-5675 5000);
FORCEPROP 1 LAST BODY_TYPE PLUMBING
J 2
(-5675 5050);
DISPLAY 0.872340 (-5675 5050);
PAINT GREEN (-5675 5050);
DISPLAY INVISIBLE (-5675 5050);
FORCEPROP 1 LAST HDL_TAP TRUE
J 2
(-6000 4875);
DISPLAY 0.872340 (-6000 4875);
DISPLAY INVISIBLE (-6000 4875);
FORCEPROP 1 LAST PATH I260
J 2
(-5673 5000);
DISPLAY 0.872340 (-5673 5000);
PAINT GREEN (-5673 5000);
DISPLAY INVISIBLE (-5673 5000);
FORCEADD TAP..1
R 2
(-5675 5100);
FORCEPROP 3 LASTPIN (-5625 5100) SIG_NAME M_J_CPU1_SA_DQS_DP<8>
J 0
(-5615 5110);
DISPLAY 0.659574 (-5615 5110);
PAINT MONO (-5615 5110);
DISPLAY INVISIBLE (-5615 5110);
FORCEPROP 1 LASTPIN (-5625 5100) BN 8
J 2
(-5613 5108);
DISPLAY 0.489362 (-5613 5108);
PAINT GREEN (-5613 5108);
FORCEPROP 2 LAST CDS_LIB mstr_standard
J 2
(-5675 5100);
DISPLAY 0.723404 (-5675 5100);
PAINT MONO (-5675 5100);
DISPLAY INVISIBLE (-5675 5100);
FORCEPROP 1 LAST BODY_TYPE PLUMBING
J 2
(-5675 5150);
DISPLAY 0.872340 (-5675 5150);
PAINT GREEN (-5675 5150);
DISPLAY INVISIBLE (-5675 5150);
FORCEPROP 1 LAST HDL_TAP TRUE
J 2
(-6000 4975);
DISPLAY 0.872340 (-6000 4975);
DISPLAY INVISIBLE (-6000 4975);
FORCEPROP 1 LAST PATH I261
J 2
(-5673 5100);
DISPLAY 0.872340 (-5673 5100);
PAINT GREEN (-5673 5100);
DISPLAY INVISIBLE (-5673 5100);
FORCEADD TAP..1
R 2
(-5675 4850);
FORCEPROP 3 LASTPIN (-5625 4850) SIG_NAME M_J_CPU1_SB_DQS_DP<0>
J 0
(-5615 4860);
DISPLAY 0.659574 (-5615 4860);
PAINT MONO (-5615 4860);
DISPLAY INVISIBLE (-5615 4860);
FORCEPROP 1 LASTPIN (-5625 4850) BN 0
J 2
(-5613 4858);
DISPLAY 0.489362 (-5613 4858);
PAINT GREEN (-5613 4858);
FORCEPROP 2 LAST CDS_LIB mstr_standard
J 2
(-5675 4850);
DISPLAY 0.723404 (-5675 4850);
PAINT MONO (-5675 4850);
DISPLAY INVISIBLE (-5675 4850);
FORCEPROP 1 LAST BODY_TYPE PLUMBING
J 2
(-5675 4900);
DISPLAY 0.872340 (-5675 4900);
PAINT GREEN (-5675 4900);
DISPLAY INVISIBLE (-5675 4900);
FORCEPROP 1 LAST HDL_TAP TRUE
J 2
(-6000 4725);
DISPLAY 0.872340 (-6000 4725);
DISPLAY INVISIBLE (-6000 4725);
FORCEPROP 1 LAST PATH I262
J 2
(-5673 4850);
DISPLAY 0.872340 (-5673 4850);
PAINT GREEN (-5673 4850);
DISPLAY INVISIBLE (-5673 4850);
FORCEADD TAP..1
R 2
(-5675 4750);
FORCEPROP 3 LASTPIN (-5625 4750) SIG_NAME M_J_CPU1_SB_DQS_DP<1>
J 0
(-5615 4760);
DISPLAY 0.659574 (-5615 4760);
PAINT MONO (-5615 4760);
DISPLAY INVISIBLE (-5615 4760);
FORCEPROP 1 LASTPIN (-5625 4750) BN 1
J 2
(-5613 4758);
DISPLAY 0.489362 (-5613 4758);
PAINT GREEN (-5613 4758);
FORCEPROP 2 LAST CDS_LIB mstr_standard
J 2
(-5675 4750);
DISPLAY 0.723404 (-5675 4750);
PAINT MONO (-5675 4750);
DISPLAY INVISIBLE (-5675 4750);
FORCEPROP 1 LAST BODY_TYPE PLUMBING
J 2
(-5675 4800);
DISPLAY 0.872340 (-5675 4800);
PAINT GREEN (-5675 4800);
DISPLAY INVISIBLE (-5675 4800);
FORCEPROP 1 LAST HDL_TAP TRUE
J 2
(-6000 4625);
DISPLAY 0.872340 (-6000 4625);
DISPLAY INVISIBLE (-6000 4625);
FORCEPROP 1 LAST PATH I263
J 2
(-5673 4750);
DISPLAY 0.872340 (-5673 4750);
PAINT GREEN (-5673 4750);
DISPLAY INVISIBLE (-5673 4750);
FORCEADD TAP..1
R 2
(-5675 4650);
FORCEPROP 3 LASTPIN (-5625 4650) SIG_NAME M_J_CPU1_SB_DQS_DP<2>
J 0
(-5615 4660);
DISPLAY 0.659574 (-5615 4660);
PAINT MONO (-5615 4660);
DISPLAY INVISIBLE (-5615 4660);
FORCEPROP 1 LASTPIN (-5625 4650) BN 2
J 2
(-5613 4658);
DISPLAY 0.489362 (-5613 4658);
PAINT GREEN (-5613 4658);
FORCEPROP 2 LAST CDS_LIB mstr_standard
J 2
(-5675 4650);
DISPLAY 0.723404 (-5675 4650);
PAINT MONO (-5675 4650);
DISPLAY INVISIBLE (-5675 4650);
FORCEPROP 1 LAST BODY_TYPE PLUMBING
J 2
(-5675 4700);
DISPLAY 0.872340 (-5675 4700);
PAINT GREEN (-5675 4700);
DISPLAY INVISIBLE (-5675 4700);
FORCEPROP 1 LAST HDL_TAP TRUE
J 2
(-6000 4525);
DISPLAY 0.872340 (-6000 4525);
DISPLAY INVISIBLE (-6000 4525);
FORCEPROP 1 LAST PATH I264
J 2
(-5673 4650);
DISPLAY 0.872340 (-5673 4650);
PAINT GREEN (-5673 4650);
DISPLAY INVISIBLE (-5673 4650);
FORCEADD TAP..1
R 2
(-5675 4550);
FORCEPROP 3 LASTPIN (-5625 4550) SIG_NAME M_J_CPU1_SB_DQS_DP<3>
J 0
(-5615 4560);
DISPLAY 0.659574 (-5615 4560);
PAINT MONO (-5615 4560);
DISPLAY INVISIBLE (-5615 4560);
FORCEPROP 1 LASTPIN (-5625 4550) BN 3
J 2
(-5613 4558);
DISPLAY 0.489362 (-5613 4558);
PAINT GREEN (-5613 4558);
FORCEPROP 2 LAST CDS_LIB mstr_standard
J 2
(-5675 4550);
DISPLAY 0.723404 (-5675 4550);
PAINT MONO (-5675 4550);
DISPLAY INVISIBLE (-5675 4550);
FORCEPROP 1 LAST BODY_TYPE PLUMBING
J 2
(-5675 4600);
DISPLAY 0.872340 (-5675 4600);
PAINT GREEN (-5675 4600);
DISPLAY INVISIBLE (-5675 4600);
FORCEPROP 1 LAST HDL_TAP TRUE
J 2
(-6000 4425);
DISPLAY 0.872340 (-6000 4425);
DISPLAY INVISIBLE (-6000 4425);
FORCEPROP 1 LAST PATH I265
J 2
(-5673 4550);
DISPLAY 0.872340 (-5673 4550);
PAINT GREEN (-5673 4550);
DISPLAY INVISIBLE (-5673 4550);
FORCEADD TAP..1
R 2
(-5675 4450);
FORCEPROP 3 LASTPIN (-5625 4450) SIG_NAME M_J_CPU1_SB_DQS_DP<4>
J 0
(-5615 4460);
DISPLAY 0.659574 (-5615 4460);
PAINT MONO (-5615 4460);
DISPLAY INVISIBLE (-5615 4460);
FORCEPROP 1 LASTPIN (-5625 4450) BN 4
J 2
(-5613 4458);
DISPLAY 0.489362 (-5613 4458);
PAINT GREEN (-5613 4458);
FORCEPROP 2 LAST CDS_LIB mstr_standard
J 2
(-5675 4450);
DISPLAY 0.723404 (-5675 4450);
PAINT MONO (-5675 4450);
DISPLAY INVISIBLE (-5675 4450);
FORCEPROP 1 LAST BODY_TYPE PLUMBING
J 2
(-5675 4500);
DISPLAY 0.872340 (-5675 4500);
PAINT GREEN (-5675 4500);
DISPLAY INVISIBLE (-5675 4500);
FORCEPROP 1 LAST HDL_TAP TRUE
J 2
(-6000 4325);
DISPLAY 0.872340 (-6000 4325);
DISPLAY INVISIBLE (-6000 4325);
FORCEPROP 1 LAST PATH I266
J 2
(-5673 4450);
DISPLAY 0.872340 (-5673 4450);
PAINT GREEN (-5673 4450);
DISPLAY INVISIBLE (-5673 4450);
FORCEADD TAP..1
R 2
(-5675 4350);
FORCEPROP 3 LASTPIN (-5625 4350) SIG_NAME M_J_CPU1_SB_DQS_DP<5>
J 0
(-5615 4360);
DISPLAY 0.659574 (-5615 4360);
PAINT MONO (-5615 4360);
DISPLAY INVISIBLE (-5615 4360);
FORCEPROP 1 LASTPIN (-5625 4350) BN 5
J 2
(-5613 4358);
DISPLAY 0.489362 (-5613 4358);
PAINT GREEN (-5613 4358);
FORCEPROP 2 LAST CDS_LIB mstr_standard
J 2
(-5675 4350);
DISPLAY 0.723404 (-5675 4350);
PAINT MONO (-5675 4350);
DISPLAY INVISIBLE (-5675 4350);
FORCEPROP 1 LAST BODY_TYPE PLUMBING
J 2
(-5675 4400);
DISPLAY 0.872340 (-5675 4400);
PAINT GREEN (-5675 4400);
DISPLAY INVISIBLE (-5675 4400);
FORCEPROP 1 LAST HDL_TAP TRUE
J 2
(-6000 4225);
DISPLAY 0.872340 (-6000 4225);
DISPLAY INVISIBLE (-6000 4225);
FORCEPROP 1 LAST PATH I267
J 2
(-5673 4350);
DISPLAY 0.872340 (-5673 4350);
PAINT GREEN (-5673 4350);
DISPLAY INVISIBLE (-5673 4350);
FORCEADD TAP..1
R 2
(-5675 4250);
FORCEPROP 3 LASTPIN (-5625 4250) SIG_NAME M_J_CPU1_SB_DQS_DP<6>
J 0
(-5615 4260);
DISPLAY 0.659574 (-5615 4260);
PAINT MONO (-5615 4260);
DISPLAY INVISIBLE (-5615 4260);
FORCEPROP 1 LASTPIN (-5625 4250) BN 6
J 2
(-5613 4258);
DISPLAY 0.489362 (-5613 4258);
PAINT GREEN (-5613 4258);
FORCEPROP 2 LAST CDS_LIB mstr_standard
J 2
(-5675 4250);
DISPLAY 0.723404 (-5675 4250);
PAINT MONO (-5675 4250);
DISPLAY INVISIBLE (-5675 4250);
FORCEPROP 1 LAST BODY_TYPE PLUMBING
J 2
(-5675 4300);
DISPLAY 0.872340 (-5675 4300);
PAINT GREEN (-5675 4300);
DISPLAY INVISIBLE (-5675 4300);
FORCEPROP 1 LAST HDL_TAP TRUE
J 2
(-6000 4125);
DISPLAY 0.872340 (-6000 4125);
DISPLAY INVISIBLE (-6000 4125);
FORCEPROP 1 LAST PATH I268
J 2
(-5673 4250);
DISPLAY 0.872340 (-5673 4250);
PAINT GREEN (-5673 4250);
DISPLAY INVISIBLE (-5673 4250);
FORCEADD TAP..1
R 2
(-5675 4150);
FORCEPROP 3 LASTPIN (-5625 4150) SIG_NAME M_J_CPU1_SB_DQS_DP<7>
J 0
(-5615 4160);
DISPLAY 0.659574 (-5615 4160);
PAINT MONO (-5615 4160);
DISPLAY INVISIBLE (-5615 4160);
FORCEPROP 1 LASTPIN (-5625 4150) BN 7
J 2
(-5613 4158);
DISPLAY 0.489362 (-5613 4158);
PAINT GREEN (-5613 4158);
FORCEPROP 2 LAST CDS_LIB mstr_standard
J 2
(-5675 4150);
DISPLAY 0.723404 (-5675 4150);
PAINT MONO (-5675 4150);
DISPLAY INVISIBLE (-5675 4150);
FORCEPROP 1 LAST BODY_TYPE PLUMBING
J 2
(-5675 4200);
DISPLAY 0.872340 (-5675 4200);
PAINT GREEN (-5675 4200);
DISPLAY INVISIBLE (-5675 4200);
FORCEPROP 1 LAST HDL_TAP TRUE
J 2
(-6000 4025);
DISPLAY 0.872340 (-6000 4025);
DISPLAY INVISIBLE (-6000 4025);
FORCEPROP 1 LAST PATH I269
J 2
(-5673 4150);
DISPLAY 0.872340 (-5673 4150);
PAINT GREEN (-5673 4150);
DISPLAY INVISIBLE (-5673 4150);
FORCEADD TAP..1
R 2
(-5875 4950);
FORCEPROP 3 LASTPIN (-5825 4950) SIG_NAME M_J_CPU1_SA_DQS_DN<9>
J 0
(-5815 4960);
DISPLAY 0.659574 (-5815 4960);
PAINT MONO (-5815 4960);
DISPLAY INVISIBLE (-5815 4960);
FORCEPROP 1 LASTPIN (-5825 4950) BN 9
J 2
(-5813 4958);
DISPLAY 0.489362 (-5813 4958);
PAINT GREEN (-5813 4958);
FORCEPROP 2 LAST CDS_LIB mstr_standard
J 2
(-5875 4950);
DISPLAY 0.723404 (-5875 4950);
PAINT MONO (-5875 4950);
DISPLAY INVISIBLE (-5875 4950);
FORCEPROP 1 LAST BODY_TYPE PLUMBING
J 2
(-5875 5000);
DISPLAY 0.872340 (-5875 5000);
PAINT GREEN (-5875 5000);
DISPLAY INVISIBLE (-5875 5000);
FORCEPROP 1 LAST HDL_TAP TRUE
J 2
(-6200 4825);
DISPLAY 0.872340 (-6200 4825);
DISPLAY INVISIBLE (-6200 4825);
FORCEPROP 1 LAST PATH I270
J 2
(-5873 4950);
DISPLAY 0.872340 (-5873 4950);
PAINT GREEN (-5873 4950);
DISPLAY INVISIBLE (-5873 4950);
FORCEADD TAP..1
R 2
(-5875 5050);
FORCEPROP 3 LASTPIN (-5825 5050) SIG_NAME M_J_CPU1_SA_DQS_DN<8>
J 0
(-5815 5060);
DISPLAY 0.659574 (-5815 5060);
PAINT MONO (-5815 5060);
DISPLAY INVISIBLE (-5815 5060);
FORCEPROP 1 LASTPIN (-5825 5050) BN 8
J 2
(-5813 5058);
DISPLAY 0.489362 (-5813 5058);
PAINT GREEN (-5813 5058);
FORCEPROP 2 LAST CDS_LIB mstr_standard
J 2
(-5875 5050);
DISPLAY 0.723404 (-5875 5050);
PAINT MONO (-5875 5050);
DISPLAY INVISIBLE (-5875 5050);
FORCEPROP 1 LAST BODY_TYPE PLUMBING
J 2
(-5875 5100);
DISPLAY 0.872340 (-5875 5100);
PAINT GREEN (-5875 5100);
DISPLAY INVISIBLE (-5875 5100);
FORCEPROP 1 LAST HDL_TAP TRUE
J 2
(-6200 4925);
DISPLAY 0.872340 (-6200 4925);
DISPLAY INVISIBLE (-6200 4925);
FORCEPROP 1 LAST PATH I271
J 2
(-5873 5050);
DISPLAY 0.872340 (-5873 5050);
PAINT GREEN (-5873 5050);
DISPLAY INVISIBLE (-5873 5050);
FORCEADD TAP..1
R 2
(-5875 4800);
FORCEPROP 3 LASTPIN (-5825 4800) SIG_NAME M_J_CPU1_SB_DQS_DN<0>
J 0
(-5815 4810);
DISPLAY 0.659574 (-5815 4810);
PAINT MONO (-5815 4810);
DISPLAY INVISIBLE (-5815 4810);
FORCEPROP 1 LASTPIN (-5825 4800) BN 0
J 2
(-5813 4808);
DISPLAY 0.489362 (-5813 4808);
PAINT GREEN (-5813 4808);
FORCEPROP 2 LAST CDS_LIB mstr_standard
J 2
(-5875 4800);
DISPLAY 0.723404 (-5875 4800);
PAINT MONO (-5875 4800);
DISPLAY INVISIBLE (-5875 4800);
FORCEPROP 1 LAST BODY_TYPE PLUMBING
J 2
(-5875 4850);
DISPLAY 0.872340 (-5875 4850);
PAINT GREEN (-5875 4850);
DISPLAY INVISIBLE (-5875 4850);
FORCEPROP 1 LAST HDL_TAP TRUE
J 2
(-6200 4675);
DISPLAY 0.872340 (-6200 4675);
DISPLAY INVISIBLE (-6200 4675);
FORCEPROP 1 LAST PATH I272
J 2
(-5873 4800);
DISPLAY 0.872340 (-5873 4800);
PAINT GREEN (-5873 4800);
DISPLAY INVISIBLE (-5873 4800);
FORCEADD TAP..1
R 2
(-5875 4700);
FORCEPROP 3 LASTPIN (-5825 4700) SIG_NAME M_J_CPU1_SB_DQS_DN<1>
J 0
(-5815 4710);
DISPLAY 0.659574 (-5815 4710);
PAINT MONO (-5815 4710);
DISPLAY INVISIBLE (-5815 4710);
FORCEPROP 1 LASTPIN (-5825 4700) BN 1
J 2
(-5813 4708);
DISPLAY 0.489362 (-5813 4708);
PAINT GREEN (-5813 4708);
FORCEPROP 2 LAST CDS_LIB mstr_standard
J 2
(-5875 4700);
DISPLAY 0.723404 (-5875 4700);
PAINT MONO (-5875 4700);
DISPLAY INVISIBLE (-5875 4700);
FORCEPROP 1 LAST BODY_TYPE PLUMBING
J 2
(-5875 4750);
DISPLAY 0.872340 (-5875 4750);
PAINT GREEN (-5875 4750);
DISPLAY INVISIBLE (-5875 4750);
FORCEPROP 1 LAST HDL_TAP TRUE
J 2
(-6200 4575);
DISPLAY 0.872340 (-6200 4575);
DISPLAY INVISIBLE (-6200 4575);
FORCEPROP 1 LAST PATH I273
J 2
(-5873 4700);
DISPLAY 0.872340 (-5873 4700);
PAINT GREEN (-5873 4700);
DISPLAY INVISIBLE (-5873 4700);
FORCEADD TAP..1
R 2
(-5875 4500);
FORCEPROP 3 LASTPIN (-5825 4500) SIG_NAME M_J_CPU1_SB_DQS_DN<3>
J 0
(-5815 4510);
DISPLAY 0.659574 (-5815 4510);
PAINT MONO (-5815 4510);
DISPLAY INVISIBLE (-5815 4510);
FORCEPROP 1 LASTPIN (-5825 4500) BN 3
J 2
(-5813 4508);
DISPLAY 0.489362 (-5813 4508);
PAINT GREEN (-5813 4508);
FORCEPROP 2 LAST CDS_LIB mstr_standard
J 2
(-5875 4500);
DISPLAY 0.723404 (-5875 4500);
PAINT MONO (-5875 4500);
DISPLAY INVISIBLE (-5875 4500);
FORCEPROP 1 LAST BODY_TYPE PLUMBING
J 2
(-5875 4550);
DISPLAY 0.872340 (-5875 4550);
PAINT GREEN (-5875 4550);
DISPLAY INVISIBLE (-5875 4550);
FORCEPROP 1 LAST HDL_TAP TRUE
J 2
(-6200 4375);
DISPLAY 0.872340 (-6200 4375);
DISPLAY INVISIBLE (-6200 4375);
FORCEPROP 1 LAST PATH I274
J 2
(-5873 4500);
DISPLAY 0.872340 (-5873 4500);
PAINT GREEN (-5873 4500);
DISPLAY INVISIBLE (-5873 4500);
FORCEADD TAP..1
R 2
(-5875 4600);
FORCEPROP 3 LASTPIN (-5825 4600) SIG_NAME M_J_CPU1_SB_DQS_DN<2>
J 0
(-5815 4610);
DISPLAY 0.659574 (-5815 4610);
PAINT MONO (-5815 4610);
DISPLAY INVISIBLE (-5815 4610);
FORCEPROP 1 LASTPIN (-5825 4600) BN 2
J 2
(-5813 4608);
DISPLAY 0.489362 (-5813 4608);
PAINT GREEN (-5813 4608);
FORCEPROP 2 LAST CDS_LIB mstr_standard
J 2
(-5875 4600);
DISPLAY 0.723404 (-5875 4600);
PAINT MONO (-5875 4600);
DISPLAY INVISIBLE (-5875 4600);
FORCEPROP 1 LAST BODY_TYPE PLUMBING
J 2
(-5875 4650);
DISPLAY 0.872340 (-5875 4650);
PAINT GREEN (-5875 4650);
DISPLAY INVISIBLE (-5875 4650);
FORCEPROP 1 LAST HDL_TAP TRUE
J 2
(-6200 4475);
DISPLAY 0.872340 (-6200 4475);
DISPLAY INVISIBLE (-6200 4475);
FORCEPROP 1 LAST PATH I275
J 2
(-5873 4600);
DISPLAY 0.872340 (-5873 4600);
PAINT GREEN (-5873 4600);
DISPLAY INVISIBLE (-5873 4600);
FORCEADD TAP..1
R 2
(-5875 4400);
FORCEPROP 3 LASTPIN (-5825 4400) SIG_NAME M_J_CPU1_SB_DQS_DN<4>
J 0
(-5815 4410);
DISPLAY 0.659574 (-5815 4410);
PAINT MONO (-5815 4410);
DISPLAY INVISIBLE (-5815 4410);
FORCEPROP 1 LASTPIN (-5825 4400) BN 4
J 2
(-5813 4408);
DISPLAY 0.489362 (-5813 4408);
PAINT GREEN (-5813 4408);
FORCEPROP 2 LAST CDS_LIB mstr_standard
J 2
(-5875 4400);
DISPLAY 0.723404 (-5875 4400);
PAINT MONO (-5875 4400);
DISPLAY INVISIBLE (-5875 4400);
FORCEPROP 1 LAST BODY_TYPE PLUMBING
J 2
(-5875 4450);
DISPLAY 0.872340 (-5875 4450);
PAINT GREEN (-5875 4450);
DISPLAY INVISIBLE (-5875 4450);
FORCEPROP 1 LAST HDL_TAP TRUE
J 2
(-6200 4275);
DISPLAY 0.872340 (-6200 4275);
DISPLAY INVISIBLE (-6200 4275);
FORCEPROP 1 LAST PATH I276
J 2
(-5873 4400);
DISPLAY 0.872340 (-5873 4400);
PAINT GREEN (-5873 4400);
DISPLAY INVISIBLE (-5873 4400);
FORCEADD TAP..1
R 2
(-5875 4300);
FORCEPROP 3 LASTPIN (-5825 4300) SIG_NAME M_J_CPU1_SB_DQS_DN<5>
J 0
(-5815 4310);
DISPLAY 0.659574 (-5815 4310);
PAINT MONO (-5815 4310);
DISPLAY INVISIBLE (-5815 4310);
FORCEPROP 1 LASTPIN (-5825 4300) BN 5
J 2
(-5813 4308);
DISPLAY 0.489362 (-5813 4308);
PAINT GREEN (-5813 4308);
FORCEPROP 2 LAST CDS_LIB mstr_standard
J 2
(-5875 4300);
DISPLAY 0.723404 (-5875 4300);
PAINT MONO (-5875 4300);
DISPLAY INVISIBLE (-5875 4300);
FORCEPROP 1 LAST BODY_TYPE PLUMBING
J 2
(-5875 4350);
DISPLAY 0.872340 (-5875 4350);
PAINT GREEN (-5875 4350);
DISPLAY INVISIBLE (-5875 4350);
FORCEPROP 1 LAST HDL_TAP TRUE
J 2
(-6200 4175);
DISPLAY 0.872340 (-6200 4175);
DISPLAY INVISIBLE (-6200 4175);
FORCEPROP 1 LAST PATH I277
J 2
(-5873 4300);
DISPLAY 0.872340 (-5873 4300);
PAINT GREEN (-5873 4300);
DISPLAY INVISIBLE (-5873 4300);
FORCEADD TAP..1
R 2
(-5875 4100);
FORCEPROP 3 LASTPIN (-5825 4100) SIG_NAME M_J_CPU1_SB_DQS_DN<7>
J 0
(-5815 4110);
DISPLAY 0.659574 (-5815 4110);
PAINT MONO (-5815 4110);
DISPLAY INVISIBLE (-5815 4110);
FORCEPROP 1 LASTPIN (-5825 4100) BN 7
J 2
(-5813 4108);
DISPLAY 0.489362 (-5813 4108);
PAINT GREEN (-5813 4108);
FORCEPROP 2 LAST CDS_LIB mstr_standard
J 2
(-5875 4100);
DISPLAY 0.723404 (-5875 4100);
PAINT MONO (-5875 4100);
DISPLAY INVISIBLE (-5875 4100);
FORCEPROP 1 LAST BODY_TYPE PLUMBING
J 2
(-5875 4150);
DISPLAY 0.872340 (-5875 4150);
PAINT GREEN (-5875 4150);
DISPLAY INVISIBLE (-5875 4150);
FORCEPROP 1 LAST HDL_TAP TRUE
J 2
(-6200 3975);
DISPLAY 0.872340 (-6200 3975);
DISPLAY INVISIBLE (-6200 3975);
FORCEPROP 1 LAST PATH I278
J 2
(-5873 4100);
DISPLAY 0.872340 (-5873 4100);
PAINT GREEN (-5873 4100);
DISPLAY INVISIBLE (-5873 4100);
FORCEADD TAP..1
R 2
(-5875 4200);
FORCEPROP 3 LASTPIN (-5825 4200) SIG_NAME M_J_CPU1_SB_DQS_DN<6>
J 0
(-5815 4210);
DISPLAY 0.659574 (-5815 4210);
PAINT MONO (-5815 4210);
DISPLAY INVISIBLE (-5815 4210);
FORCEPROP 1 LASTPIN (-5825 4200) BN 6
J 2
(-5813 4208);
DISPLAY 0.489362 (-5813 4208);
PAINT GREEN (-5813 4208);
FORCEPROP 2 LAST CDS_LIB mstr_standard
J 2
(-5875 4200);
DISPLAY 0.723404 (-5875 4200);
PAINT MONO (-5875 4200);
DISPLAY INVISIBLE (-5875 4200);
FORCEPROP 1 LAST BODY_TYPE PLUMBING
J 2
(-5875 4250);
DISPLAY 0.872340 (-5875 4250);
PAINT GREEN (-5875 4250);
DISPLAY INVISIBLE (-5875 4250);
FORCEPROP 1 LAST HDL_TAP TRUE
J 2
(-6200 4075);
DISPLAY 0.872340 (-6200 4075);
DISPLAY INVISIBLE (-6200 4075);
FORCEPROP 1 LAST PATH I279
J 2
(-5873 4200);
DISPLAY 0.872340 (-5873 4200);
PAINT GREEN (-5873 4200);
DISPLAY INVISIBLE (-5873 4200);
FORCEADD OFFPAGE..3
R 2
(-6575 5875);
FORCEPROP 2 LAST $XR0 107 
J 0
(-6885 5875);
DISPLAY 0.638298 (-6885 5875);
PAINT MONO (-6885 5875);
FORCEPROP 2 LAST CDS_LIB standard
J 0
(-6575 5875);
DISPLAY INVISIBLE (-6575 5875);
FORCEPROP 1 LAST OFFPAGE TRUE
J 2
(-6900 5750);
DISPLAY 0.872340 (-6900 5750);
PAINT GREEN (-6900 5750);
DISPLAY INVISIBLE (-6900 5750);
FORCEPROP 1 LAST COMMENT_BODY TRUE
J 2
(-6525 5775);
DISPLAY 0.872340 (-6525 5775);
PAINT GREEN (-6525 5775);
DISPLAY INVISIBLE (-6525 5775);
FORCEPROP 2 LAST PATH I280
J 0
(-6875 5925);
DISPLAY 1.021277 (-6875 5925);
DISPLAY INVISIBLE (-6875 5925);
FORCEADD OFFPAGE..3
R 2
(-6575 5925);
FORCEPROP 2 LAST $XR0 107 
J 0
(-6885 5925);
DISPLAY 0.638298 (-6885 5925);
PAINT MONO (-6885 5925);
FORCEPROP 2 LAST CDS_LIB standard
J 0
(-6575 5925);
DISPLAY INVISIBLE (-6575 5925);
FORCEPROP 1 LAST OFFPAGE TRUE
J 2
(-6900 5800);
DISPLAY 0.872340 (-6900 5800);
PAINT GREEN (-6900 5800);
DISPLAY INVISIBLE (-6900 5800);
FORCEPROP 1 LAST COMMENT_BODY TRUE
J 2
(-6525 5825);
DISPLAY 0.872340 (-6525 5825);
PAINT GREEN (-6525 5825);
DISPLAY INVISIBLE (-6525 5825);
FORCEPROP 2 LAST PATH I281
J 0
(-6875 5975);
DISPLAY 1.021277 (-6875 5975);
DISPLAY INVISIBLE (-6875 5975);
FORCEADD OFFPAGE..3
R 2
(-6575 4825);
FORCEPROP 2 LAST $XR0 107 
J 0
(-6885 4825);
DISPLAY 0.638298 (-6885 4825);
PAINT MONO (-6885 4825);
FORCEPROP 2 LAST CDS_LIB standard
J 0
(-6575 4825);
DISPLAY INVISIBLE (-6575 4825);
FORCEPROP 1 LAST OFFPAGE TRUE
J 2
(-6900 4700);
DISPLAY 0.872340 (-6900 4700);
PAINT GREEN (-6900 4700);
DISPLAY INVISIBLE (-6900 4700);
FORCEPROP 1 LAST COMMENT_BODY TRUE
J 2
(-6525 4725);
DISPLAY 0.872340 (-6525 4725);
PAINT GREEN (-6525 4725);
DISPLAY INVISIBLE (-6525 4725);
FORCEPROP 2 LAST PATH I282
J 0
(-6875 4875);
DISPLAY 1.021277 (-6875 4875);
DISPLAY INVISIBLE (-6875 4875);
FORCEADD OFFPAGE..3
R 2
(-6575 4875);
FORCEPROP 2 LAST $XR0 107 
J 0
(-6885 4875);
DISPLAY 0.638298 (-6885 4875);
PAINT MONO (-6885 4875);
FORCEPROP 2 LAST CDS_LIB standard
J 0
(-6575 4875);
DISPLAY INVISIBLE (-6575 4875);
FORCEPROP 1 LAST OFFPAGE TRUE
J 2
(-6900 4750);
DISPLAY 0.872340 (-6900 4750);
PAINT GREEN (-6900 4750);
DISPLAY INVISIBLE (-6900 4750);
FORCEPROP 1 LAST COMMENT_BODY TRUE
J 2
(-6525 4775);
DISPLAY 0.872340 (-6525 4775);
PAINT GREEN (-6525 4775);
DISPLAY INVISIBLE (-6525 4775);
FORCEPROP 2 LAST PATH I283
J 0
(-6875 4925);
DISPLAY 1.021277 (-6875 4925);
DISPLAY INVISIBLE (-6875 4925);
FORCEADD TAP..1
R 2
(-5675 4050);
FORCEPROP 3 LASTPIN (-5625 4050) SIG_NAME M_J_CPU1_SB_DQS_DP<8>
J 0
(-5615 4060);
DISPLAY 0.659574 (-5615 4060);
PAINT MONO (-5615 4060);
DISPLAY INVISIBLE (-5615 4060);
FORCEPROP 1 LASTPIN (-5625 4050) BN 8
J 2
(-5613 4058);
DISPLAY 0.489362 (-5613 4058);
PAINT GREEN (-5613 4058);
FORCEPROP 2 LAST CDS_LIB mstr_standard
J 2
(-5675 4050);
DISPLAY 0.723404 (-5675 4050);
PAINT MONO (-5675 4050);
DISPLAY INVISIBLE (-5675 4050);
FORCEPROP 1 LAST BODY_TYPE PLUMBING
J 2
(-5675 4100);
DISPLAY 0.872340 (-5675 4100);
PAINT GREEN (-5675 4100);
DISPLAY INVISIBLE (-5675 4100);
FORCEPROP 1 LAST HDL_TAP TRUE
J 2
(-6000 3925);
DISPLAY 0.872340 (-6000 3925);
DISPLAY INVISIBLE (-6000 3925);
FORCEPROP 1 LAST PATH I284
J 2
(-5673 4050);
DISPLAY 0.872340 (-5673 4050);
PAINT GREEN (-5673 4050);
DISPLAY INVISIBLE (-5673 4050);
FORCEADD TAP..1
R 2
(-5675 3950);
FORCEPROP 3 LASTPIN (-5625 3950) SIG_NAME M_J_CPU1_SB_DQS_DP<9>
J 0
(-5615 3960);
DISPLAY 0.659574 (-5615 3960);
PAINT MONO (-5615 3960);
DISPLAY INVISIBLE (-5615 3960);
FORCEPROP 1 LASTPIN (-5625 3950) BN 9
J 2
(-5613 3958);
DISPLAY 0.489362 (-5613 3958);
PAINT GREEN (-5613 3958);
FORCEPROP 2 LAST CDS_LIB mstr_standard
J 2
(-5675 3950);
DISPLAY 0.723404 (-5675 3950);
PAINT MONO (-5675 3950);
DISPLAY INVISIBLE (-5675 3950);
FORCEPROP 1 LAST BODY_TYPE PLUMBING
J 2
(-5675 4000);
DISPLAY 0.872340 (-5675 4000);
PAINT GREEN (-5675 4000);
DISPLAY INVISIBLE (-5675 4000);
FORCEPROP 1 LAST HDL_TAP TRUE
J 2
(-6000 3825);
DISPLAY 0.872340 (-6000 3825);
DISPLAY INVISIBLE (-6000 3825);
FORCEPROP 1 LAST PATH I285
J 2
(-5673 3950);
DISPLAY 0.872340 (-5673 3950);
PAINT GREEN (-5673 3950);
DISPLAY INVISIBLE (-5673 3950);
FORCEADD TAP..1
R 2
(-5875 4000);
FORCEPROP 3 LASTPIN (-5825 4000) SIG_NAME M_J_CPU1_SB_DQS_DN<8>
J 0
(-5815 4010);
DISPLAY 0.659574 (-5815 4010);
PAINT MONO (-5815 4010);
DISPLAY INVISIBLE (-5815 4010);
FORCEPROP 1 LASTPIN (-5825 4000) BN 8
J 2
(-5813 4008);
DISPLAY 0.489362 (-5813 4008);
PAINT GREEN (-5813 4008);
FORCEPROP 2 LAST CDS_LIB mstr_standard
J 2
(-5875 4000);
DISPLAY 0.723404 (-5875 4000);
PAINT MONO (-5875 4000);
DISPLAY INVISIBLE (-5875 4000);
FORCEPROP 1 LAST BODY_TYPE PLUMBING
J 2
(-5875 4050);
DISPLAY 0.872340 (-5875 4050);
PAINT GREEN (-5875 4050);
DISPLAY INVISIBLE (-5875 4050);
FORCEPROP 1 LAST HDL_TAP TRUE
J 2
(-6200 3875);
DISPLAY 0.872340 (-6200 3875);
DISPLAY INVISIBLE (-6200 3875);
FORCEPROP 1 LAST PATH I286
J 2
(-5873 4000);
DISPLAY 0.872340 (-5873 4000);
PAINT GREEN (-5873 4000);
DISPLAY INVISIBLE (-5873 4000);
FORCEADD TAP..1
R 2
(-5875 3900);
FORCEPROP 3 LASTPIN (-5825 3900) SIG_NAME M_J_CPU1_SB_DQS_DN<9>
J 0
(-5815 3910);
DISPLAY 0.659574 (-5815 3910);
PAINT MONO (-5815 3910);
DISPLAY INVISIBLE (-5815 3910);
FORCEPROP 1 LASTPIN (-5825 3900) BN 9
J 2
(-5813 3908);
DISPLAY 0.489362 (-5813 3908);
PAINT GREEN (-5813 3908);
FORCEPROP 2 LAST CDS_LIB mstr_standard
J 2
(-5875 3900);
DISPLAY 0.723404 (-5875 3900);
PAINT MONO (-5875 3900);
DISPLAY INVISIBLE (-5875 3900);
FORCEPROP 1 LAST BODY_TYPE PLUMBING
J 2
(-5875 3950);
DISPLAY 0.872340 (-5875 3950);
PAINT GREEN (-5875 3950);
DISPLAY INVISIBLE (-5875 3950);
FORCEPROP 1 LAST HDL_TAP TRUE
J 2
(-6200 3775);
DISPLAY 0.872340 (-6200 3775);
DISPLAY INVISIBLE (-6200 3775);
FORCEPROP 1 LAST PATH I287
J 2
(-5873 3900);
DISPLAY 0.872340 (-5873 3900);
PAINT GREEN (-5873 3900);
DISPLAY INVISIBLE (-5873 3900);
FORCEADD TAP..1
R 2
(-5875 3750);
FORCEPROP 3 LASTPIN (-5825 3750) SIG_NAME M_J_CPU1_SA_CA<0>
J 0
(-5815 3760);
DISPLAY 0.659574 (-5815 3760);
PAINT MONO (-5815 3760);
DISPLAY INVISIBLE (-5815 3760);
FORCEPROP 1 LASTPIN (-5825 3750) BN 0
J 2
(-5813 3758);
DISPLAY 0.489362 (-5813 3758);
PAINT GREEN (-5813 3758);
FORCEPROP 2 LAST CDS_LIB mstr_standard
J 0
(-5875 3750);
DISPLAY 0.723404 (-5875 3750);
PAINT MONO (-5875 3750);
DISPLAY INVISIBLE (-5875 3750);
FORCEPROP 1 LAST BODY_TYPE PLUMBING
J 2
(-5875 3800);
DISPLAY 0.872340 (-5875 3800);
PAINT GREEN (-5875 3800);
DISPLAY INVISIBLE (-5875 3800);
FORCEPROP 1 LAST HDL_TAP TRUE
J 2
(-6200 3625);
DISPLAY 0.872340 (-6200 3625);
DISPLAY INVISIBLE (-6200 3625);
FORCEPROP 1 LAST PATH I288
J 2
(-5873 3750);
DISPLAY 0.872340 (-5873 3750);
PAINT GREEN (-5873 3750);
DISPLAY INVISIBLE (-5873 3750);
FORCEADD TAP..1
R 2
(-5875 3700);
FORCEPROP 3 LASTPIN (-5825 3700) SIG_NAME M_J_CPU1_SA_CA<1>
J 0
(-5815 3710);
DISPLAY 0.659574 (-5815 3710);
PAINT MONO (-5815 3710);
DISPLAY INVISIBLE (-5815 3710);
FORCEPROP 1 LASTPIN (-5825 3700) BN 1
J 2
(-5813 3708);
DISPLAY 0.489362 (-5813 3708);
PAINT GREEN (-5813 3708);
FORCEPROP 2 LAST CDS_LIB mstr_standard
J 0
(-5875 3700);
DISPLAY 0.723404 (-5875 3700);
PAINT MONO (-5875 3700);
DISPLAY INVISIBLE (-5875 3700);
FORCEPROP 1 LAST BODY_TYPE PLUMBING
J 2
(-5875 3750);
DISPLAY 0.872340 (-5875 3750);
PAINT GREEN (-5875 3750);
DISPLAY INVISIBLE (-5875 3750);
FORCEPROP 1 LAST HDL_TAP TRUE
J 2
(-6200 3575);
DISPLAY 0.872340 (-6200 3575);
DISPLAY INVISIBLE (-6200 3575);
FORCEPROP 1 LAST PATH I289
J 2
(-5873 3700);
DISPLAY 0.872340 (-5873 3700);
PAINT GREEN (-5873 3700);
DISPLAY INVISIBLE (-5873 3700);
FORCEADD TAP..1
R 2
(-5875 3600);
FORCEPROP 3 LASTPIN (-5825 3600) SIG_NAME M_J_CPU1_SA_CA<3>
J 0
(-5815 3610);
DISPLAY 0.659574 (-5815 3610);
PAINT MONO (-5815 3610);
DISPLAY INVISIBLE (-5815 3610);
FORCEPROP 1 LASTPIN (-5825 3600) BN 3
J 2
(-5813 3608);
DISPLAY 0.489362 (-5813 3608);
PAINT GREEN (-5813 3608);
FORCEPROP 2 LAST CDS_LIB mstr_standard
J 0
(-5875 3600);
DISPLAY 0.723404 (-5875 3600);
PAINT MONO (-5875 3600);
DISPLAY INVISIBLE (-5875 3600);
FORCEPROP 1 LAST BODY_TYPE PLUMBING
J 2
(-5875 3650);
DISPLAY 0.872340 (-5875 3650);
PAINT GREEN (-5875 3650);
DISPLAY INVISIBLE (-5875 3650);
FORCEPROP 1 LAST HDL_TAP TRUE
J 2
(-6200 3475);
DISPLAY 0.872340 (-6200 3475);
DISPLAY INVISIBLE (-6200 3475);
FORCEPROP 1 LAST PATH I290
J 2
(-5873 3600);
DISPLAY 0.872340 (-5873 3600);
PAINT GREEN (-5873 3600);
DISPLAY INVISIBLE (-5873 3600);
FORCEADD TAP..1
R 2
(-5875 3650);
FORCEPROP 3 LASTPIN (-5825 3650) SIG_NAME M_J_CPU1_SA_CA<2>
J 0
(-5815 3660);
DISPLAY 0.659574 (-5815 3660);
PAINT MONO (-5815 3660);
DISPLAY INVISIBLE (-5815 3660);
FORCEPROP 1 LASTPIN (-5825 3650) BN 2
J 2
(-5813 3658);
DISPLAY 0.489362 (-5813 3658);
PAINT GREEN (-5813 3658);
FORCEPROP 2 LAST CDS_LIB mstr_standard
J 0
(-5875 3650);
DISPLAY 0.723404 (-5875 3650);
PAINT MONO (-5875 3650);
DISPLAY INVISIBLE (-5875 3650);
FORCEPROP 1 LAST BODY_TYPE PLUMBING
J 2
(-5875 3700);
DISPLAY 0.872340 (-5875 3700);
PAINT GREEN (-5875 3700);
DISPLAY INVISIBLE (-5875 3700);
FORCEPROP 1 LAST HDL_TAP TRUE
J 2
(-6200 3525);
DISPLAY 0.872340 (-6200 3525);
DISPLAY INVISIBLE (-6200 3525);
FORCEPROP 1 LAST PATH I291
J 2
(-5873 3650);
DISPLAY 0.872340 (-5873 3650);
PAINT GREEN (-5873 3650);
DISPLAY INVISIBLE (-5873 3650);
FORCEADD TAP..1
R 2
(-5875 3550);
FORCEPROP 3 LASTPIN (-5825 3550) SIG_NAME M_J_CPU1_SA_CA<4>
J 0
(-5815 3560);
DISPLAY 0.659574 (-5815 3560);
PAINT MONO (-5815 3560);
DISPLAY INVISIBLE (-5815 3560);
FORCEPROP 1 LASTPIN (-5825 3550) BN 4
J 2
(-5813 3558);
DISPLAY 0.489362 (-5813 3558);
PAINT GREEN (-5813 3558);
FORCEPROP 2 LAST CDS_LIB mstr_standard
J 0
(-5875 3550);
DISPLAY 0.723404 (-5875 3550);
PAINT MONO (-5875 3550);
DISPLAY INVISIBLE (-5875 3550);
FORCEPROP 1 LAST BODY_TYPE PLUMBING
J 2
(-5875 3600);
DISPLAY 0.872340 (-5875 3600);
PAINT GREEN (-5875 3600);
DISPLAY INVISIBLE (-5875 3600);
FORCEPROP 1 LAST HDL_TAP TRUE
J 2
(-6200 3425);
DISPLAY 0.872340 (-6200 3425);
DISPLAY INVISIBLE (-6200 3425);
FORCEPROP 1 LAST PATH I292
J 2
(-5873 3550);
DISPLAY 0.872340 (-5873 3550);
PAINT GREEN (-5873 3550);
DISPLAY INVISIBLE (-5873 3550);
FORCEADD TAP..1
R 2
(-5875 3500);
FORCEPROP 3 LASTPIN (-5825 3500) SIG_NAME M_J_CPU1_SA_CA<5>
J 0
(-5815 3510);
DISPLAY 0.659574 (-5815 3510);
PAINT MONO (-5815 3510);
DISPLAY INVISIBLE (-5815 3510);
FORCEPROP 1 LASTPIN (-5825 3500) BN 5
J 2
(-5813 3508);
DISPLAY 0.489362 (-5813 3508);
PAINT GREEN (-5813 3508);
FORCEPROP 2 LAST CDS_LIB mstr_standard
J 0
(-5875 3500);
DISPLAY 0.723404 (-5875 3500);
PAINT MONO (-5875 3500);
DISPLAY INVISIBLE (-5875 3500);
FORCEPROP 1 LAST BODY_TYPE PLUMBING
J 2
(-5875 3550);
DISPLAY 0.872340 (-5875 3550);
PAINT GREEN (-5875 3550);
DISPLAY INVISIBLE (-5875 3550);
FORCEPROP 1 LAST HDL_TAP TRUE
J 2
(-6200 3375);
DISPLAY 0.872340 (-6200 3375);
DISPLAY INVISIBLE (-6200 3375);
FORCEPROP 1 LAST PATH I293
J 2
(-5873 3500);
DISPLAY 0.872340 (-5873 3500);
PAINT GREEN (-5873 3500);
DISPLAY INVISIBLE (-5873 3500);
FORCEADD TAP..1
R 2
(-5875 3450);
FORCEPROP 3 LASTPIN (-5825 3450) SIG_NAME M_J_CPU1_SA_CA<6>
J 0
(-5815 3460);
DISPLAY 0.659574 (-5815 3460);
PAINT MONO (-5815 3460);
DISPLAY INVISIBLE (-5815 3460);
FORCEPROP 1 LASTPIN (-5825 3450) BN 6
J 2
(-5813 3458);
DISPLAY 0.489362 (-5813 3458);
PAINT GREEN (-5813 3458);
FORCEPROP 2 LAST CDS_LIB mstr_standard
J 0
(-5875 3450);
DISPLAY 0.723404 (-5875 3450);
PAINT MONO (-5875 3450);
DISPLAY INVISIBLE (-5875 3450);
FORCEPROP 1 LAST BODY_TYPE PLUMBING
J 2
(-5875 3500);
DISPLAY 0.872340 (-5875 3500);
PAINT GREEN (-5875 3500);
DISPLAY INVISIBLE (-5875 3500);
FORCEPROP 1 LAST HDL_TAP TRUE
J 2
(-6200 3325);
DISPLAY 0.872340 (-6200 3325);
DISPLAY INVISIBLE (-6200 3325);
FORCEPROP 1 LAST PATH I294
J 2
(-5873 3450);
DISPLAY 0.872340 (-5873 3450);
PAINT GREEN (-5873 3450);
DISPLAY INVISIBLE (-5873 3450);
FORCEADD TAP..1
R 2
(-5875 3350);
FORCEPROP 3 LASTPIN (-5825 3350) SIG_NAME M_J_CPU1_SB_CA<0>
J 0
(-5815 3360);
DISPLAY 0.659574 (-5815 3360);
PAINT MONO (-5815 3360);
DISPLAY INVISIBLE (-5815 3360);
FORCEPROP 1 LASTPIN (-5825 3350) BN 0
J 2
(-5813 3358);
DISPLAY 0.489362 (-5813 3358);
PAINT GREEN (-5813 3358);
FORCEPROP 2 LAST CDS_LIB mstr_standard
J 0
(-5875 3350);
DISPLAY 0.723404 (-5875 3350);
PAINT MONO (-5875 3350);
DISPLAY INVISIBLE (-5875 3350);
FORCEPROP 1 LAST BODY_TYPE PLUMBING
J 2
(-5875 3400);
DISPLAY 0.872340 (-5875 3400);
PAINT GREEN (-5875 3400);
DISPLAY INVISIBLE (-5875 3400);
FORCEPROP 1 LAST HDL_TAP TRUE
J 2
(-6200 3225);
DISPLAY 0.872340 (-6200 3225);
DISPLAY INVISIBLE (-6200 3225);
FORCEPROP 1 LAST PATH I295
J 2
(-5873 3350);
DISPLAY 0.872340 (-5873 3350);
PAINT GREEN (-5873 3350);
DISPLAY INVISIBLE (-5873 3350);
FORCEADD TAP..1
R 2
(-5875 3250);
FORCEPROP 3 LASTPIN (-5825 3250) SIG_NAME M_J_CPU1_SB_CA<2>
J 0
(-5815 3260);
DISPLAY 0.659574 (-5815 3260);
PAINT MONO (-5815 3260);
DISPLAY INVISIBLE (-5815 3260);
FORCEPROP 1 LASTPIN (-5825 3250) BN 2
J 2
(-5813 3258);
DISPLAY 0.489362 (-5813 3258);
PAINT GREEN (-5813 3258);
FORCEPROP 2 LAST CDS_LIB mstr_standard
J 0
(-5875 3250);
DISPLAY 0.723404 (-5875 3250);
PAINT MONO (-5875 3250);
DISPLAY INVISIBLE (-5875 3250);
FORCEPROP 1 LAST BODY_TYPE PLUMBING
J 2
(-5875 3300);
DISPLAY 0.872340 (-5875 3300);
PAINT GREEN (-5875 3300);
DISPLAY INVISIBLE (-5875 3300);
FORCEPROP 1 LAST HDL_TAP TRUE
J 2
(-6200 3125);
DISPLAY 0.872340 (-6200 3125);
DISPLAY INVISIBLE (-6200 3125);
FORCEPROP 1 LAST PATH I296
J 2
(-5873 3250);
DISPLAY 0.872340 (-5873 3250);
PAINT GREEN (-5873 3250);
DISPLAY INVISIBLE (-5873 3250);
FORCEADD TAP..1
R 2
(-5875 3300);
FORCEPROP 3 LASTPIN (-5825 3300) SIG_NAME M_J_CPU1_SB_CA<1>
J 0
(-5815 3310);
DISPLAY 0.659574 (-5815 3310);
PAINT MONO (-5815 3310);
DISPLAY INVISIBLE (-5815 3310);
FORCEPROP 1 LASTPIN (-5825 3300) BN 1
J 2
(-5813 3308);
DISPLAY 0.489362 (-5813 3308);
PAINT GREEN (-5813 3308);
FORCEPROP 2 LAST CDS_LIB mstr_standard
J 0
(-5875 3300);
DISPLAY 0.723404 (-5875 3300);
PAINT MONO (-5875 3300);
DISPLAY INVISIBLE (-5875 3300);
FORCEPROP 1 LAST BODY_TYPE PLUMBING
J 2
(-5875 3350);
DISPLAY 0.872340 (-5875 3350);
PAINT GREEN (-5875 3350);
DISPLAY INVISIBLE (-5875 3350);
FORCEPROP 1 LAST HDL_TAP TRUE
J 2
(-6200 3175);
DISPLAY 0.872340 (-6200 3175);
DISPLAY INVISIBLE (-6200 3175);
FORCEPROP 1 LAST PATH I297
J 2
(-5873 3300);
DISPLAY 0.872340 (-5873 3300);
PAINT GREEN (-5873 3300);
DISPLAY INVISIBLE (-5873 3300);
FORCEADD TAP..1
R 2
(-5875 3200);
FORCEPROP 3 LASTPIN (-5825 3200) SIG_NAME M_J_CPU1_SB_CA<3>
J 0
(-5815 3210);
DISPLAY 0.659574 (-5815 3210);
PAINT MONO (-5815 3210);
DISPLAY INVISIBLE (-5815 3210);
FORCEPROP 1 LASTPIN (-5825 3200) BN 3
J 2
(-5813 3208);
DISPLAY 0.489362 (-5813 3208);
PAINT GREEN (-5813 3208);
FORCEPROP 2 LAST CDS_LIB mstr_standard
J 0
(-5875 3200);
DISPLAY 0.723404 (-5875 3200);
PAINT MONO (-5875 3200);
DISPLAY INVISIBLE (-5875 3200);
FORCEPROP 1 LAST BODY_TYPE PLUMBING
J 2
(-5875 3250);
DISPLAY 0.872340 (-5875 3250);
PAINT GREEN (-5875 3250);
DISPLAY INVISIBLE (-5875 3250);
FORCEPROP 1 LAST HDL_TAP TRUE
J 2
(-6200 3075);
DISPLAY 0.872340 (-6200 3075);
DISPLAY INVISIBLE (-6200 3075);
FORCEPROP 1 LAST PATH I298
J 2
(-5873 3200);
DISPLAY 0.872340 (-5873 3200);
PAINT GREEN (-5873 3200);
DISPLAY INVISIBLE (-5873 3200);
FORCEADD TAP..1
R 2
(-5875 3150);
FORCEPROP 3 LASTPIN (-5825 3150) SIG_NAME M_J_CPU1_SB_CA<4>
J 0
(-5815 3160);
DISPLAY 0.659574 (-5815 3160);
PAINT MONO (-5815 3160);
DISPLAY INVISIBLE (-5815 3160);
FORCEPROP 1 LASTPIN (-5825 3150) BN 4
J 2
(-5813 3158);
DISPLAY 0.489362 (-5813 3158);
PAINT GREEN (-5813 3158);
FORCEPROP 2 LAST CDS_LIB mstr_standard
J 0
(-5875 3150);
DISPLAY 0.723404 (-5875 3150);
PAINT MONO (-5875 3150);
DISPLAY INVISIBLE (-5875 3150);
FORCEPROP 1 LAST BODY_TYPE PLUMBING
J 2
(-5875 3200);
DISPLAY 0.872340 (-5875 3200);
PAINT GREEN (-5875 3200);
DISPLAY INVISIBLE (-5875 3200);
FORCEPROP 1 LAST HDL_TAP TRUE
J 2
(-6200 3025);
DISPLAY 0.872340 (-6200 3025);
DISPLAY INVISIBLE (-6200 3025);
FORCEPROP 1 LAST PATH I299
J 2
(-5873 3150);
DISPLAY 0.872340 (-5873 3150);
PAINT GREEN (-5873 3150);
DISPLAY INVISIBLE (-5873 3150);
FORCEADD TAP..1
R 2
(-5875 3100);
FORCEPROP 3 LASTPIN (-5825 3100) SIG_NAME M_J_CPU1_SB_CA<5>
J 0
(-5815 3110);
DISPLAY 0.659574 (-5815 3110);
PAINT MONO (-5815 3110);
DISPLAY INVISIBLE (-5815 3110);
FORCEPROP 1 LASTPIN (-5825 3100) BN 5
J 2
(-5813 3108);
DISPLAY 0.489362 (-5813 3108);
PAINT GREEN (-5813 3108);
FORCEPROP 2 LAST CDS_LIB mstr_standard
J 0
(-5875 3100);
DISPLAY 0.723404 (-5875 3100);
PAINT MONO (-5875 3100);
DISPLAY INVISIBLE (-5875 3100);
FORCEPROP 1 LAST BODY_TYPE PLUMBING
J 2
(-5875 3150);
DISPLAY 0.872340 (-5875 3150);
PAINT GREEN (-5875 3150);
DISPLAY INVISIBLE (-5875 3150);
FORCEPROP 1 LAST HDL_TAP TRUE
J 2
(-6200 2975);
DISPLAY 0.872340 (-6200 2975);
DISPLAY INVISIBLE (-6200 2975);
FORCEPROP 1 LAST PATH I300
J 2
(-5873 3100);
DISPLAY 0.872340 (-5873 3100);
PAINT GREEN (-5873 3100);
DISPLAY INVISIBLE (-5873 3100);
FORCEADD TAP..1
R 2
(-5875 3050);
FORCEPROP 3 LASTPIN (-5825 3050) SIG_NAME M_J_CPU1_SB_CA<6>
J 0
(-5815 3060);
DISPLAY 0.659574 (-5815 3060);
PAINT MONO (-5815 3060);
DISPLAY INVISIBLE (-5815 3060);
FORCEPROP 1 LASTPIN (-5825 3050) BN 6
J 2
(-5813 3058);
DISPLAY 0.489362 (-5813 3058);
PAINT GREEN (-5813 3058);
FORCEPROP 2 LAST CDS_LIB mstr_standard
J 0
(-5875 3050);
DISPLAY 0.723404 (-5875 3050);
PAINT MONO (-5875 3050);
DISPLAY INVISIBLE (-5875 3050);
FORCEPROP 1 LAST BODY_TYPE PLUMBING
J 2
(-5875 3100);
DISPLAY 0.872340 (-5875 3100);
PAINT GREEN (-5875 3100);
DISPLAY INVISIBLE (-5875 3100);
FORCEPROP 1 LAST HDL_TAP TRUE
J 2
(-6200 2925);
DISPLAY 0.872340 (-6200 2925);
DISPLAY INVISIBLE (-6200 2925);
FORCEPROP 1 LAST PATH I301
J 2
(-5873 3050);
DISPLAY 0.872340 (-5873 3050);
PAINT GREEN (-5873 3050);
DISPLAY INVISIBLE (-5873 3050);
FORCEADD OFFPAGE..2
R 2
(-6475 3775);
FORCEPROP 2 LAST $XR0 107 
J 0
(-6730 3775);
DISPLAY 0.638298 (-6730 3775);
PAINT MONO (-6730 3775);
FORCEPROP 2 LAST CDS_LIB standard
J 0
(-6475 3775);
DISPLAY INVISIBLE (-6475 3775);
FORCEPROP 1 LAST OFFPAGE TRUE
J 2
(-6800 3650);
DISPLAY 0.872340 (-6800 3650);
PAINT GREEN (-6800 3650);
DISPLAY INVISIBLE (-6800 3650);
FORCEPROP 1 LAST COMMENT_BODY TRUE
J 2
(-6430 3680);
DISPLAY 0.872340 (-6430 3680);
PAINT GREEN (-6430 3680);
DISPLAY INVISIBLE (-6430 3680);
FORCEPROP 2 LAST PATH I302
J 0
(-6750 3825);
DISPLAY 1.021277 (-6750 3825);
DISPLAY INVISIBLE (-6750 3825);
FORCEADD OFFPAGE..2
R 2
(-6475 3375);
FORCEPROP 2 LAST $XR0 107 
J 0
(-6730 3375);
DISPLAY 0.638298 (-6730 3375);
PAINT MONO (-6730 3375);
FORCEPROP 2 LAST CDS_LIB standard
J 0
(-6475 3375);
DISPLAY INVISIBLE (-6475 3375);
FORCEPROP 1 LAST OFFPAGE TRUE
J 2
(-6800 3250);
DISPLAY 0.872340 (-6800 3250);
PAINT GREEN (-6800 3250);
DISPLAY INVISIBLE (-6800 3250);
FORCEPROP 1 LAST COMMENT_BODY TRUE
J 2
(-6430 3280);
DISPLAY 0.872340 (-6430 3280);
PAINT GREEN (-6430 3280);
DISPLAY INVISIBLE (-6430 3280);
FORCEPROP 2 LAST PATH I303
J 0
(-6750 3425);
DISPLAY 1.021277 (-6750 3425);
DISPLAY INVISIBLE (-6750 3425);
FORCEADD OFFPAGE..2
R 2
(-6475 2900);
FORCEPROP 2 LAST $XR0 107 
J 0
(-6730 2900);
DISPLAY 0.638298 (-6730 2900);
PAINT MONO (-6730 2900);
FORCEPROP 2 LAST CDS_LIB standard
J 0
(-6475 2900);
DISPLAY INVISIBLE (-6475 2900);
FORCEPROP 1 LAST OFFPAGE TRUE
J 2
(-6800 2775);
DISPLAY 0.872340 (-6800 2775);
PAINT GREEN (-6800 2775);
DISPLAY INVISIBLE (-6800 2775);
FORCEPROP 1 LAST COMMENT_BODY TRUE
J 2
(-6430 2805);
DISPLAY 0.872340 (-6430 2805);
PAINT GREEN (-6430 2805);
DISPLAY INVISIBLE (-6430 2805);
FORCEPROP 2 LAST PATH I304
J 0
(-6750 2950);
DISPLAY 1.021277 (-6750 2950);
DISPLAY INVISIBLE (-6750 2950);
FORCEADD OFFPAGE..2
R 2
(-6475 2850);
FORCEPROP 2 LAST $XR0 107 
J 0
(-6730 2850);
DISPLAY 0.638298 (-6730 2850);
PAINT MONO (-6730 2850);
FORCEPROP 2 LAST CDS_LIB standard
J 0
(-6475 2850);
DISPLAY INVISIBLE (-6475 2850);
FORCEPROP 1 LAST OFFPAGE TRUE
J 2
(-6800 2725);
DISPLAY 0.872340 (-6800 2725);
PAINT GREEN (-6800 2725);
DISPLAY INVISIBLE (-6800 2725);
FORCEPROP 1 LAST COMMENT_BODY TRUE
J 2
(-6430 2755);
DISPLAY 0.872340 (-6430 2755);
PAINT GREEN (-6430 2755);
DISPLAY INVISIBLE (-6430 2755);
FORCEPROP 2 LAST PATH I305
J 0
(-6750 2900);
DISPLAY 1.021277 (-6750 2900);
DISPLAY INVISIBLE (-6750 2900);
FORCEADD OFFPAGE..2
R 2
(-6475 2750);
FORCEPROP 2 LAST $XR0 107 
J 0
(-6730 2750);
DISPLAY 0.638298 (-6730 2750);
PAINT MONO (-6730 2750);
FORCEPROP 2 LAST CDS_LIB standard
J 0
(-6475 2750);
DISPLAY INVISIBLE (-6475 2750);
FORCEPROP 1 LAST OFFPAGE TRUE
J 2
(-6800 2625);
DISPLAY 0.872340 (-6800 2625);
PAINT GREEN (-6800 2625);
DISPLAY INVISIBLE (-6800 2625);
FORCEPROP 1 LAST COMMENT_BODY TRUE
J 2
(-6430 2655);
DISPLAY 0.872340 (-6430 2655);
PAINT GREEN (-6430 2655);
DISPLAY INVISIBLE (-6430 2655);
FORCEPROP 2 LAST PATH I306
J 0
(-6750 2800);
DISPLAY 1.021277 (-6750 2800);
DISPLAY INVISIBLE (-6750 2800);
FORCEADD OFFPAGE..2
R 2
(-6475 2700);
FORCEPROP 2 LAST $XR0 107 
J 0
(-6730 2700);
DISPLAY 0.638298 (-6730 2700);
PAINT MONO (-6730 2700);
FORCEPROP 2 LAST CDS_LIB standard
J 0
(-6475 2700);
DISPLAY INVISIBLE (-6475 2700);
FORCEPROP 1 LAST OFFPAGE TRUE
J 2
(-6800 2575);
DISPLAY 0.872340 (-6800 2575);
PAINT GREEN (-6800 2575);
DISPLAY INVISIBLE (-6800 2575);
FORCEPROP 1 LAST COMMENT_BODY TRUE
J 2
(-6430 2605);
DISPLAY 0.872340 (-6430 2605);
PAINT GREEN (-6430 2605);
DISPLAY INVISIBLE (-6430 2605);
FORCEPROP 2 LAST PATH I307
J 0
(-6750 2750);
DISPLAY 1.021277 (-6750 2750);
DISPLAY INVISIBLE (-6750 2750);
FORCEADD OFFPAGE..1
(-6475 2600);
FORCEPROP 2 LAST $XR0 107 
J 0
(-6757 2600);
DISPLAY 0.638298 (-6757 2600);
PAINT MONO (-6757 2600);
FORCEPROP 2 LAST CDS_LIB standard
J 0
(-6475 2600);
DISPLAY INVISIBLE (-6475 2600);
FORCEPROP 1 LAST OFFPAGE TRUE
J 0
(-6150 2475);
DISPLAY 0.872340 (-6150 2475);
PAINT GREEN (-6150 2475);
DISPLAY INVISIBLE (-6150 2475);
FORCEPROP 1 LAST COMMENT_BODY TRUE
J 0
(-6350 2500);
DISPLAY 0.872340 (-6350 2500);
PAINT GREEN (-6350 2500);
DISPLAY INVISIBLE (-6350 2500);
FORCEPROP 2 LAST PATH I308
J 0
(-6725 2650);
DISPLAY 1.021277 (-6725 2650);
DISPLAY INVISIBLE (-6725 2650);
FORCEADD OFFPAGE..2
R 2
(-6475 2400);
FORCEPROP 2 LAST $XR0 107 
J 0
(-6730 2400);
DISPLAY 0.638298 (-6730 2400);
PAINT MONO (-6730 2400);
FORCEPROP 2 LAST CDS_LIB standard
J 0
(-6475 2400);
DISPLAY INVISIBLE (-6475 2400);
FORCEPROP 1 LAST OFFPAGE TRUE
J 2
(-6800 2275);
DISPLAY 0.872340 (-6800 2275);
PAINT GREEN (-6800 2275);
DISPLAY INVISIBLE (-6800 2275);
FORCEPROP 1 LAST COMMENT_BODY TRUE
J 2
(-6430 2305);
DISPLAY 0.872340 (-6430 2305);
PAINT GREEN (-6430 2305);
DISPLAY INVISIBLE (-6430 2305);
FORCEPROP 2 LAST PATH I309
J 0
(-6750 2450);
DISPLAY 1.021277 (-6750 2450);
DISPLAY INVISIBLE (-6750 2450);
FORCEADD OFFPAGE..2
R 2
(-6475 2350);
FORCEPROP 2 LAST $XR0 107 
J 0
(-6730 2350);
DISPLAY 0.638298 (-6730 2350);
PAINT MONO (-6730 2350);
FORCEPROP 2 LAST CDS_LIB standard
J 0
(-6475 2350);
DISPLAY INVISIBLE (-6475 2350);
FORCEPROP 1 LAST OFFPAGE TRUE
J 2
(-6800 2225);
DISPLAY 0.872340 (-6800 2225);
PAINT GREEN (-6800 2225);
DISPLAY INVISIBLE (-6800 2225);
FORCEPROP 1 LAST COMMENT_BODY TRUE
J 2
(-6430 2255);
DISPLAY 0.872340 (-6430 2255);
PAINT GREEN (-6430 2255);
DISPLAY INVISIBLE (-6430 2255);
FORCEPROP 2 LAST PATH I310
J 0
(-6750 2400);
DISPLAY 1.021277 (-6750 2400);
DISPLAY INVISIBLE (-6750 2400);
FORCEADD OFFPAGE..5
(-6475 2500);
FORCEPROP 2 LAST $XR0 107 
J 0
(-6730 2500);
DISPLAY 0.638298 (-6730 2500);
PAINT MONO (-6730 2500);
FORCEPROP 2 LAST CDS_LIB mstr_standard
J 0
(-6475 2500);
DISPLAY INVISIBLE (-6475 2500);
FORCEPROP 1 LAST OFFPAGE TRUE
J 0
(-6150 2375);
DISPLAY 0.872340 (-6150 2375);
PAINT GREEN (-6150 2375);
DISPLAY INVISIBLE (-6150 2375);
FORCEPROP 1 LAST COMMENT_BODY TRUE
J 0
(-6375 2425);
DISPLAY 0.872340 (-6375 2425);
PAINT GREEN (-6375 2425);
DISPLAY INVISIBLE (-6375 2425);
FORCEPROP 2 LAST PATH I311
J 0
(-6750 2550);
DISPLAY 1.021277 (-6750 2550);
DISPLAY INVISIBLE (-6750 2550);
FORCEADD OFFPAGE..5
(-6475 2150);
FORCEPROP 2 LAST $XR0 107 
J 0
(-6730 2150);
DISPLAY 0.638298 (-6730 2150);
PAINT MONO (-6730 2150);
FORCEPROP 2 LAST CDS_LIB standard
J 0
(-6475 2150);
DISPLAY INVISIBLE (-6475 2150);
FORCEPROP 1 LAST OFFPAGE TRUE
J 0
(-6150 2025);
DISPLAY 0.872340 (-6150 2025);
PAINT GREEN (-6150 2025);
DISPLAY INVISIBLE (-6150 2025);
FORCEPROP 1 LAST COMMENT_BODY TRUE
J 0
(-6375 2075);
DISPLAY 0.872340 (-6375 2075);
PAINT GREEN (-6375 2075);
DISPLAY INVISIBLE (-6375 2075);
FORCEPROP 2 LAST PATH I312
J 0
(-6750 2200);
DISPLAY 1.021277 (-6750 2200);
DISPLAY INVISIBLE (-6750 2200);
FORCEADD OFFPAGE..1
(-6475 2250);
FORCEPROP 2 LAST $XR0 107 
J 0
(-6757 2250);
DISPLAY 0.638298 (-6757 2250);
PAINT MONO (-6757 2250);
FORCEPROP 2 LAST CDS_LIB standard
J 0
(-6475 2250);
DISPLAY INVISIBLE (-6475 2250);
FORCEPROP 1 LAST OFFPAGE TRUE
J 0
(-6150 2125);
DISPLAY 0.872340 (-6150 2125);
PAINT GREEN (-6150 2125);
DISPLAY INVISIBLE (-6150 2125);
FORCEPROP 1 LAST COMMENT_BODY TRUE
J 0
(-6350 2150);
DISPLAY 0.872340 (-6350 2150);
PAINT GREEN (-6350 2150);
DISPLAY INVISIBLE (-6350 2150);
FORCEPROP 2 LAST PATH I313
J 0
(-6725 2300);
DISPLAY 1.021277 (-6725 2300);
DISPLAY INVISIBLE (-6725 2300);
FORCEADD Q_RES..1
(-6550 2050);
FORCEPROP 1 LAST LOCATION R509
J 0
(-6875 2050);
DISPLAY 0.489362 (-6875 2050);
PAINT SKYBLUE (-6875 2050);
FORCEPROP 0 LAST $SEC 1
J 0
(-6725 2100);
DISPLAY 0.680851 (-6725 2100);
PAINT MONO (-6725 2100);
DISPLAY INVISIBLE (-6725 2100);
FORCEPROP 0 LAST CDS_SEC 1
J 0
(-6725 2100);
DISPLAY 1.021277 (-6725 2100);
DISPLAY INVISIBLE (-6725 2100);
FORCEPROP 1 LASTPIN (-6650 2050) $PN 1
J 0
(-6638 2062);
DISPLAY 0.489362 (-6638 2062);
PAINT MONO (-6638 2062);
FORCEPROP 1 LASTPIN (-6450 2050) $PN 2
J 0
(-6488 2062);
DISPLAY 0.489362 (-6488 2062);
PAINT MONO (-6488 2062);
FORCEPROP 1 LAST PACK_TYPE 0402LF
J 0
(-6875 2025);
DISPLAY 0.489362 (-6875 2025);
PAINT SKYBLUE (-6875 2025);
FORCEPROP 1 LAST TOLERANCE 1%
J 0
(-6275 2050);
DISPLAY 0.489362 (-6275 2050);
PAINT SKYBLUE (-6275 2050);
FORCEPROP 1 LAST VALUE 15
J 2
(-6225 2050);
DISPLAY 0.489362 (-6225 2050);
PAINT SKYBLUE (-6225 2050);
FORCEPROP 1 LAST MATERIAL CHIP
J 0
(-6675 2175);
DISPLAY 0.638298 (-6675 2175);
PAINT SKYBLUE (-6675 2175);
DISPLAY INVISIBLE (-6675 2175);
FORCEPROP 1 LAST WATTAGE 1/16W
J 2
(-6325 2175);
DISPLAY 0.638298 (-6325 2175);
PAINT SKYBLUE (-6325 2175);
DISPLAY INVISIBLE (-6325 2175);
FORCEPROP 2 LAST CDS_LIB pure_quanta
J 0
(-6550 2050);
DISPLAY INVISIBLE (-6550 2050);
FORCEPROP 1 LAST PATH I314
J 0
(-6600 2200);
DISPLAY 0.978723 (-6600 2200);
PAINT WHITE (-6600 2200);
DISPLAY INVISIBLE (-6600 2200);
FORCEPROP 1 LAST PART_NUMBER CS01502FB03
J 0
(-6450 2025);
DISPLAY 0.489362 (-6450 2025);
PAINT SKYBLUE (-6450 2025);
DISPLAY INVISIBLE (-6450 2025);
FORCEADD OFFPAGE..5
(-6475 1950);
FORCEPROP 2 LAST $XR0 107 
J 0
(-6730 1950);
DISPLAY 0.638298 (-6730 1950);
PAINT MONO (-6730 1950);
FORCEPROP 2 LAST CDS_LIB standard
J 0
(-6475 1950);
DISPLAY INVISIBLE (-6475 1950);
FORCEPROP 1 LAST OFFPAGE TRUE
J 0
(-6150 1825);
DISPLAY 0.872340 (-6150 1825);
PAINT GREEN (-6150 1825);
DISPLAY INVISIBLE (-6150 1825);
FORCEPROP 1 LAST COMMENT_BODY TRUE
J 0
(-6375 1875);
DISPLAY 0.872340 (-6375 1875);
PAINT GREEN (-6375 1875);
DISPLAY INVISIBLE (-6375 1875);
FORCEPROP 2 LAST PATH I315
J 0
(-6750 2000);
DISPLAY 1.021277 (-6750 2000);
DISPLAY INVISIBLE (-6750 2000);
FORCEADD OFFPAGE..1
(-7425 2050);
FORCEPROP 2 LAST $XR0 107 
J 0
(-7677 2050);
DISPLAY 0.638298 (-7677 2050);
PAINT MONO (-7677 2050);
FORCEPROP 2 LAST CDS_LIB mstr_standard
J 0
(-7425 2050);
DISPLAY INVISIBLE (-7425 2050);
FORCEPROP 1 LAST OFFPAGE TRUE
J 0
(-7100 1925);
DISPLAY 0.872340 (-7100 1925);
PAINT GREEN (-7100 1925);
DISPLAY INVISIBLE (-7100 1925);
FORCEPROP 1 LAST COMMENT_BODY TRUE
J 0
(-7300 1950);
DISPLAY 0.872340 (-7300 1950);
PAINT GREEN (-7300 1950);
DISPLAY INVISIBLE (-7300 1950);
FORCEPROP 2 LAST PATH I316
J 0
(-7675 2100);
DISPLAY 1.021277 (-7675 2100);
DISPLAY INVISIBLE (-7675 2100);
FORCEADD CAD_NOTE..1
(-7600 2350);
FORCEPROP 0 LAST L1 R1983 PLACE CLOSE TO CPU < 25MM
J 0
(-7750 2225);
DISPLAY 0.617021 (-7750 2225);
PAINT WHITE (-7750 2225);
FORCEPROP 2 LAST CDS_LIB pure_quanta_power
J 0
(-7600 2350);
DISPLAY INVISIBLE (-7600 2350);
FORCEPROP 1 LAST COMMENT_BODY TRUE
J 0
(-7575 2450);
DISPLAY 0.574468 (-7575 2450);
PAINT WHITE (-7575 2450);
DISPLAY INVISIBLE (-7575 2450);
FORCEADD QUANTA_TITLE_BLOCK_C..1
(0 0);
FORCEPROP 0 LAST CDS_CON_LAST_MODIFIED Thu Sep 14 16:11:57 2023
J 0
(-1885 15);
DISPLAY INVISIBLE (-1885 15);
FORCEPROP 1 LAST CUSTOM_TXT_CDS <CON_LAST_MODIFIED>
J 0
(-1885 15);
DISPLAY 0.978723 (-1885 15);
FORCEPROP 2 LAST CUSTOM_TXT_CDS <XR_PAGE_TITLE>
J 0
(-7890 5250);
DISPLAY 0.638298 (-7890 5250);
PAINT PINK (-7890 5250);
DISPLAY INVISIBLE (-7890 5250);
FORCEPROP 1 LAST CUSTOM_TXT_CDS <NAME_2>
J 0
(-3175 50);
FORCEPROP 1 LAST CUSTOM_TXT_CDS <NAME_1>
J 0
(-3175 175);
FORCEPROP 1 LAST CUSTOM_TXT_CDS <Q_NUMBER>
J 0
(-1403 103);
DISPLAY 1.212766 (-1403 103);
FORCEPROP 1 LAST CUSTOM_TXT_CDS <Q_PROJ>
J 0
(-2382 102);
DISPLAY 1.212766 (-2382 102);
FORCEPROP 1 LAST CUSTOM_TXT_CDS <Q_REV>
J 0
(-184 103);
DISPLAY 1.212766 (-184 103);
FORCEPROP 1 LAST CUSTOM_TXT_CDS <CON_PAGE_NUM> OF <CON_TOTAL_PAGES>
J 0
(-446 18);
DISPLAY 0.978723 (-446 18);
FORCEPROP 1 LAST Q_TITLE CPU1 DDR CHJ
J 0
(-9366 26);
DISPLAY 2.446809 (-9366 26);
PAINT GREEN (-9366 26);
FORCEPROP 2 LAST PAGE_BORDER TRUE
J 0
(-7890 5250);
DISPLAY 0.638298 (-7890 5250);
PAINT PINK (-7890 5250);
DISPLAY INVISIBLE (-7890 5250);
FORCEPROP 1 LAST CDS_LMAN_SYM_OUTLINE -9475,6775,100,-125
J 0
(0 0);
DISPLAY 0.468085 (0 0);
PAINT GREEN (0 0);
DISPLAY INVISIBLE (0 0);
FORCEPROP 2 LAST CDS_LIB pure_quanta
J 0
(0 0);
DISPLAY INVISIBLE (0 0);
FORCEPROP 2 LAST CDS_XR_PAGE_TITLE CR-46 : @T6G_MB_LIB.T6G(SCH_1):PAGE46
J 0
(-7890 5250);
DISPLAY 0.638298 (-7890 5250);
PAINT PINK (-7890 5250);
DISPLAY INVISIBLE (-7890 5250);
FORCEPROP 1 LAST Q_DEPT BU9
J 1
(-3763 49);
DISPLAY 1.957447 (-3763 49);
PAINT GREEN (-3763 49);
DISPLAY INVISIBLE (-3763 49);
FORCEPROP 1 LAST COMMENT_BODY TRUE
J 0
(12 -13);
DISPLAY 0.978723 (12 -13);
PAINT GREEN (12 -13);
DISPLAY INVISIBLE (12 -13);
WIRE 17 -1 (-3200 5225)(-3200 5175);
WIRE 17 -1 (-3200 5275)(-3200 5225);
WIRE 17 -1 (-3200 5175)(-3200 5125);
WIRE 17 -1 (-3200 5025)(-3200 5125);
WIRE 17 -1 (-3200 5325)(-3200 5275);
WIRE 17 -1 (-3200 5375)(-3200 5325);
WIRE 17 -1 (-3200 4975)(-3200 5025);
WIRE 17 -1 (-3200 4925)(-3200 4975);
WIRE 17 -1 (-3200 5425)(-3200 5375);
WIRE 17 -1 (-3200 5475)(-3200 5425);
WIRE 17 -1 (-3200 4875)(-3200 4925);
WIRE 17 -1 (-3200 4875)(-3200 4825);
WIRE 17 -1 (-3200 5575)(-3200 5475);
WIRE 17 -1 (-3200 5625)(-3200 5575);
WIRE 17 -1 (-3200 4825)(-3200 4775);
WIRE 17 -1 (-3200 4775)(-3200 4725);
WIRE 17 -1 (-3200 5675)(-3200 5625);
WIRE 17 -1 (-3200 5725)(-3200 5675);
WIRE 17 -1 (-3200 4725)(-3200 4675);
WIRE 17 -1 (-3200 4675)(-3200 4575);
WIRE 17 -1 (-3200 5775)(-3200 5725);
WIRE 17 -1 (-3200 5825)(-3200 5775);
WIRE 17 -1 (-3200 4575)(-3200 4525);
WIRE 17 -1 (-3200 4525)(-3200 4475);
WIRE 17 -1 (-3200 5875)(-3200 5825);
WIRE 17 -1 (-3200 5925)(-3200 5875);
WIRE 17 -1 (-3200 4475)(-3200 4425);
WIRE 17 -1 (-3200 4375)(-3200 4425);
WIRE 17 -1 (-3200 5925)(-2575 5925);
FORCEPROP 2 LAST SIG_NAME M_J_CPU1_SA_DQ<31:0>
J 2
(-2635 5935);
DISPLAY 0.489362 (-2635 5935);
WIRE 17 -1 (-3200 4275)(-3200 4325);
WIRE 17 -1 (-3200 4225)(-3200 4275);
WIRE 17 -1 (-3200 4325)(-3200 4375);
WIRE 17 -1 (-3200 4125)(-2575 4125);
FORCEPROP 2 LAST SIG_NAME M_J_CPU1_SB_DQ<31:0>
J 2
(-2635 4135);
DISPLAY 0.489362 (-2635 4135);
WIRE 17 -1 (-3200 3125)(-3200 3175);
WIRE 17 -1 (-3200 3075)(-3200 3125);
WIRE 17 -1 (-3200 3175)(-3200 3225);
WIRE 17 -1 (-3200 3225)(-3200 3325);
WIRE 17 -1 (-3200 3075)(-3200 3025);
WIRE 17 -1 (-3200 3025)(-3200 2975);
WIRE 17 -1 (-3200 3375)(-3200 3325);
WIRE 17 -1 (-3200 3425)(-3200 3375);
WIRE 17 -1 (-3200 2975)(-3200 2925);
WIRE 17 -1 (-3200 2925)(-3200 2875);
WIRE 17 -1 (-3200 3475)(-3200 3425);
WIRE 17 -1 (-3200 3525)(-3200 3475);
WIRE 17 -1 (-3200 2875)(-3200 2775);
WIRE 17 -1 (-3200 2775)(-3200 2725);
WIRE 17 -1 (-3200 3575)(-3200 3525);
WIRE 17 -1 (-3200 3625)(-3200 3575);
WIRE 17 -1 (-3200 2725)(-3200 2675);
WIRE 17 -1 (-3200 2675)(-3200 2625);
WIRE 17 -1 (-3200 3675)(-3200 3625);
WIRE 17 -1 (-3200 3775)(-3200 3675);
WIRE 17 -1 (-3200 2575)(-3200 2625);
WIRE 17 -1 (-3200 2525)(-3200 2575);
WIRE 17 -1 (-3200 3825)(-3200 3775);
WIRE 17 -1 (-3200 3875)(-3200 3825);
WIRE 17 -1 (-3200 2475)(-3200 2525);
WIRE 17 -1 (-3200 2425)(-3200 2475);
WIRE 17 -1 (-3200 3925)(-3200 3875);
WIRE 17 -1 (-3200 3975)(-3200 3925);
WIRE 17 -1 (-3200 4025)(-3200 3975);
WIRE 17 -1 (-3200 4075)(-3200 4025);
WIRE 17 -1 (-3200 4125)(-3200 4075);
WIRE 17 -1 (-3200 2075)(-3200 2125);
WIRE 17 -1 (-3200 2025)(-3200 2075);
WIRE 17 -1 (-3200 2125)(-3200 2175);
WIRE 17 -1 (-3200 2225)(-3200 2175);
WIRE 17 -1 (-3200 1975)(-3200 2025);
WIRE 17 -1 (-3200 2225)(-3200 2275);
WIRE 17 -1 (-3200 2325)(-3200 2275);
WIRE 17 -1 (-3200 2325)(-3200 2350);
WIRE 17 -1 (-3200 2350)(-2700 2350);
FORCEPROP 2 LAST SIG_NAME M_J_CPU1_SA_CB<7:0>
J 2
(-2700 2360);
DISPLAY 0.489362 (-2700 2360);
WIRE 17 -1 (-3200 1525)(-3200 1575);
WIRE 17 -1 (-3200 1575)(-3200 1625);
WIRE 17 -1 (-3200 1625)(-3200 1675);
WIRE 17 -1 (-3200 1675)(-3200 1725);
WIRE 17 -1 (-3200 1775)(-3200 1725);
WIRE 17 -1 (-3200 1775)(-3200 1825);
WIRE 17 -1 (-3200 1875)(-3200 1825);
WIRE 17 -1 (-3200 1875)(-3200 1900);
WIRE 17 -1 (-3200 1900)(-2700 1900);
FORCEPROP 2 LAST SIG_NAME M_J_CPU1_SB_CB<7:0>
J 2
(-2700 1910);
DISPLAY 0.489362 (-2700 1910);
WIRE 17 -1 (-5725 5825)(-5725 5725);
WIRE 17 -1 (-5725 5925)(-5725 5825);
WIRE 17 -1 (-5725 5725)(-5725 5625);
WIRE 17 -1 (-5725 5625)(-5725 5525);
WIRE 17 -1 (-5725 5925)(-6525 5925);
FORCEPROP 2 LAST SIG_NAME M_J_CPU1_SA_DQS_DP<9:0>
J 2
(-5960 5935);
DISPLAY 0.489362 (-5960 5935);
WIRE 17 -1 (-5725 5225)(-5725 5325);
WIRE 17 -1 (-5725 5225)(-5725 5125);
WIRE 17 -1 (-5725 5325)(-5725 5425);
WIRE 17 -1 (-5725 5425)(-5725 5525);
WIRE 17 -1 (-5725 5125)(-5725 5025);
WIRE 17 -1 (-5925 5275)(-5925 5375);
WIRE 17 -1 (-5925 5175)(-5925 5275);
WIRE 17 -1 (-5925 5375)(-5925 5475);
WIRE 17 -1 (-5925 5575)(-5925 5475);
WIRE 17 -1 (-5925 5175)(-5925 5075);
WIRE 17 -1 (-5925 5075)(-5925 4975);
WIRE 17 -1 (-5925 5675)(-5925 5575);
WIRE 17 -1 (-5925 5775)(-5925 5675);
WIRE 17 -1 (-5925 5875)(-5925 5775);
FORCEPROP 2 LAST SIG_NAME M_J_CPU1_SA_DQS_DN<9:0>
J 2
(-5960 5885);
DISPLAY 0.489362 (-5960 5885);
WIRE 17 -1 (-5725 4775)(-5725 4675);
WIRE 17 -1 (-5725 4875)(-5725 4775);
WIRE 17 -1 (-5725 4675)(-5725 4575);
WIRE 17 -1 (-5725 4575)(-5725 4475);
WIRE 17 -1 (-5725 4875)(-6525 4875);
FORCEPROP 2 LAST SIG_NAME M_J_CPU1_SB_DQS_DP<9:0>
J 2
(-5960 4885);
DISPLAY 0.489362 (-5960 4885);
WIRE 17 -1 (-5725 4175)(-5725 4275);
WIRE 17 -1 (-5725 4175)(-5725 4075);
WIRE 17 -1 (-5725 4275)(-5725 4375);
WIRE 17 -1 (-5725 4375)(-5725 4475);
WIRE 17 -1 (-5725 4075)(-5725 3975);
WIRE 17 -1 (-5925 4125)(-5925 4225);
WIRE 17 -1 (-5925 4125)(-5925 4025);
WIRE 17 -1 (-5925 4225)(-5925 4325);
WIRE 17 -1 (-5925 4325)(-5925 4425);
WIRE 17 -1 (-5925 4025)(-5925 3925);
WIRE 17 -1 (-5925 4525)(-5925 4425);
WIRE 17 -1 (-5925 4625)(-5925 4525);
WIRE 17 -1 (-5925 4725)(-5925 4625);
WIRE 17 -1 (-5925 4825)(-5925 4725);
FORCEPROP 2 LAST SIG_NAME M_J_CPU1_SB_DQS_DN<9:0>
J 2
(-5960 4835);
DISPLAY 0.489362 (-5960 4835);
WIRE 17 -1 (-5925 3125)(-5925 3175);
WIRE 17 -1 (-5925 3075)(-5925 3125);
WIRE 17 -1 (-5925 3175)(-5925 3225);
WIRE 17 -1 (-5925 3225)(-5925 3275);
WIRE 17 -1 (-5925 3275)(-5925 3325);
WIRE 17 -1 (-5925 3325)(-5925 3375);
WIRE 17 -1 (-5925 3375)(-6425 3375);
FORCEPROP 2 LAST SIG_NAME M_J_CPU1_SB_CA<6:0>
J 0
(-6425 3385);
DISPLAY 0.489362 (-6425 3385);
WIRE 17 -1 (-5925 3575)(-5925 3625);
WIRE 17 -1 (-5925 3525)(-5925 3575);
WIRE 17 -1 (-5925 3625)(-5925 3675);
WIRE 17 -1 (-5925 3675)(-5925 3725);
WIRE 17 -1 (-5925 3475)(-5925 3525);
WIRE 17 -1 (-5925 3725)(-5925 3775);
WIRE 17 -1 (-5925 3775)(-6425 3775);
FORCEPROP 2 LAST SIG_NAME M_J_CPU1_SA_CA<6:0>
J 0
(-6425 3785);
DISPLAY 0.489362 (-6425 3785);
WIRE 17 -1 (-5925 5875)(-6525 5875);
WIRE 17 -1 (-5925 4825)(-6525 4825);
WIRE 16 -1 (-7375 2050)(-6650 2050);
FORCEPROP 2 LAST SIG_NAME M_J_CPU1_ALERT_N
J 0
(-7335 2060);
DISPLAY 0.489362 (-7335 2060);
WIRE 16 -1 (-6450 2050)(-5325 2050);
FORCEPROP 2 LAST SIG_NAME M_J_CPU1_ALERT_R_N
J 0
(-6160 2060);
DISPLAY 0.489362 (-6160 2060);
FORCEPROP 2 LASTPROP $XRERR UNIQUE?
J 0
(-6400 2060);
DISPLAY 0.638298 (-6400 2060);
PAINT MONO (-6400 2060);
DISPLAY INVISIBLE (-6400 2060);
WIRE 16 -1 (-6425 1100)(-5325 1100);
FORCEPROP 2 LAST SIG_NAME TP_M_J_CPU1_SA_TEST39J
J 0
(-6410 1110);
DISPLAY 0.489362 (-6410 1110);
FORCEPROP 2 LASTPROP $XRERR UNIQUE?
J 0
(-6665 1100);
DISPLAY 0.638298 (-6665 1100);
PAINT MONO (-6665 1100);
DISPLAY INVISIBLE (-6665 1100);
WIRE 16 -1 (-6425 2900)(-5325 2900);
FORCEPROP 2 LAST SIG_NAME M_J_CPU1_CLK_DP<0>
J 0
(-6425 2910);
DISPLAY 0.489362 (-6425 2910);
WIRE 16 -1 (-6425 2850)(-5325 2850);
FORCEPROP 2 LAST SIG_NAME M_J_CPU1_CLK_DN<0>
J 0
(-6425 2860);
DISPLAY 0.489362 (-6425 2860);
WIRE 16 -1 (-6425 2750)(-5325 2750);
FORCEPROP 2 LAST SIG_NAME M_J_CPU1_SA_CS_N<0>
J 0
(-6425 2760);
DISPLAY 0.489362 (-6425 2760);
WIRE 16 -1 (-6425 2700)(-5325 2700);
FORCEPROP 2 LAST SIG_NAME M_J_CPU1_SA_CS_N<1>
J 0
(-6425 2710);
DISPLAY 0.489362 (-6425 2710);
WIRE 16 -1 (-6425 2600)(-5325 2600);
FORCEPROP 2 LAST SIG_NAME M_J_CPU1_SA_RSP<0>
J 0
(-6425 2610);
DISPLAY 0.489362 (-6425 2610);
WIRE 16 -1 (-6425 2400)(-5325 2400);
FORCEPROP 2 LAST SIG_NAME M_J_CPU1_SB_CS_N<0>
J 0
(-6425 2410);
DISPLAY 0.489362 (-6425 2410);
WIRE 16 -1 (-6425 2350)(-5325 2350);
FORCEPROP 2 LAST SIG_NAME M_J_CPU1_SB_CS_N<1>
J 0
(-6425 2360);
DISPLAY 0.489362 (-6425 2360);
WIRE 16 -1 (-6425 2500)(-5325 2500);
FORCEPROP 2 LAST SIG_NAME M_J_CPU1_SA_PAR
J 0
(-6425 2510);
DISPLAY 0.489362 (-6425 2510);
WIRE 16 -1 (-6425 2150)(-5325 2150);
FORCEPROP 2 LAST SIG_NAME M_J_CPU1_SB_PAR
J 0
(-6425 2160);
DISPLAY 0.489362 (-6425 2160);
WIRE 16 -1 (-6425 2250)(-5325 2250);
FORCEPROP 2 LAST SIG_NAME M_J_CPU1_SB_RSP<0>
J 0
(-6425 2260);
DISPLAY 0.489362 (-6425 2260);
WIRE 16 -1 (-6425 1950)(-5325 1950);
FORCEPROP 2 LAST SIG_NAME M_J_CPU1_RESET_N
J 0
(-6425 1960);
DISPLAY 0.489362 (-6425 1960);
WIRE 16 -1 (-5825 3050)(-5325 3050);
WIRE 16 -1 (-5825 3500)(-5325 3500);
WIRE 16 -1 (-5825 3450)(-5325 3450);
WIRE 16 -1 (-5825 3750)(-5325 3750);
WIRE 16 -1 (-5825 3700)(-5325 3700);
WIRE 16 -1 (-5825 3650)(-5325 3650);
WIRE 16 -1 (-5825 3600)(-5325 3600);
WIRE 16 -1 (-5825 3550)(-5325 3550);
WIRE 16 -1 (-5825 3350)(-5325 3350);
WIRE 16 -1 (-5825 3300)(-5325 3300);
WIRE 16 -1 (-5825 3250)(-5325 3250);
WIRE 16 -1 (-5825 3200)(-5325 3200);
WIRE 16 -1 (-5825 3150)(-5325 3150);
WIRE 16 -1 (-5825 3100)(-5325 3100);
WIRE 16 -1 (-5825 4000)(-5325 4000);
WIRE 16 -1 (-5825 3900)(-5325 3900);
WIRE 16 -1 (-5625 4050)(-5325 4050);
WIRE 16 -1 (-5625 3950)(-5325 3950);
WIRE 16 -1 (-5825 4400)(-5325 4400);
WIRE 16 -1 (-5825 4800)(-5325 4800);
WIRE 16 -1 (-5825 5050)(-5325 5050);
WIRE 16 -1 (-5825 4950)(-5325 4950);
WIRE 16 -1 (-5825 4700)(-5325 4700);
WIRE 16 -1 (-5825 4600)(-5325 4600);
WIRE 16 -1 (-5825 4500)(-5325 4500);
WIRE 16 -1 (-5825 4300)(-5325 4300);
WIRE 16 -1 (-5825 4200)(-5325 4200);
WIRE 16 -1 (-5825 4100)(-5325 4100);
WIRE 16 -1 (-5625 4350)(-5325 4350);
WIRE 16 -1 (-5625 4550)(-5325 4550);
WIRE 16 -1 (-5625 4450)(-5325 4450);
WIRE 16 -1 (-5625 4250)(-5325 4250);
WIRE 16 -1 (-5625 4150)(-5325 4150);
WIRE 16 -1 (-5625 5100)(-5325 5100);
WIRE 16 -1 (-5625 5000)(-5325 5000);
WIRE 16 -1 (-5625 4850)(-5325 4850);
WIRE 16 -1 (-5625 4750)(-5325 4750);
WIRE 16 -1 (-5625 4650)(-5325 4650);
WIRE 16 -1 (-5825 5450)(-5325 5450);
WIRE 16 -1 (-5825 5350)(-5325 5350);
WIRE 16 -1 (-5825 5150)(-5325 5150);
WIRE 16 -1 (-5825 5850)(-5325 5850);
WIRE 16 -1 (-5825 5750)(-5325 5750);
WIRE 16 -1 (-5825 5650)(-5325 5650);
WIRE 16 -1 (-5825 5550)(-5325 5550);
WIRE 16 -1 (-5825 5250)(-5325 5250);
WIRE 16 -1 (-5625 5500)(-5325 5500);
WIRE 16 -1 (-5625 5600)(-5325 5600);
WIRE 16 -1 (-5625 5400)(-5325 5400);
WIRE 16 -1 (-5625 5300)(-5325 5300);
WIRE 16 -1 (-5625 5200)(-5325 5200);
WIRE 16 -1 (-5625 5900)(-5325 5900);
WIRE 16 -1 (-5625 5800)(-5325 5800);
WIRE 16 -1 (-5625 5700)(-5325 5700);
WIRE 16 -1 (-3725 2000)(-3300 2000);
WIRE 16 -1 (-3725 1950)(-3300 1950);
WIRE 16 -1 (-3725 1850)(-3300 1850);
WIRE 16 -1 (-3725 1800)(-3300 1800);
WIRE 16 -1 (-3725 1750)(-3300 1750);
WIRE 16 -1 (-3725 1700)(-3300 1700);
WIRE 16 -1 (-3725 1650)(-3300 1650);
WIRE 16 -1 (-3725 1600)(-3300 1600);
WIRE 16 -1 (-3725 1550)(-3300 1550);
WIRE 16 -1 (-3725 1500)(-3300 1500);
WIRE 16 -1 (-3725 2300)(-3300 2300);
WIRE 16 -1 (-3725 2250)(-3300 2250);
WIRE 16 -1 (-3725 2200)(-3300 2200);
WIRE 16 -1 (-3725 2150)(-3300 2150);
WIRE 16 -1 (-3725 2100)(-3300 2100);
WIRE 16 -1 (-3725 2050)(-3300 2050);
WIRE 16 -1 (-3725 3050)(-3300 3050);
WIRE 16 -1 (-3725 3000)(-3300 3000);
WIRE 16 -1 (-3725 2950)(-3300 2950);
WIRE 16 -1 (-3725 2900)(-3300 2900);
WIRE 16 -1 (-3725 2850)(-3300 2850);
WIRE 16 -1 (-3725 2750)(-3300 2750);
WIRE 16 -1 (-3725 2700)(-3300 2700);
WIRE 16 -1 (-3725 2650)(-3300 2650);
WIRE 16 -1 (-3725 2600)(-3300 2600);
WIRE 16 -1 (-3725 2550)(-3300 2550);
WIRE 16 -1 (-3725 2500)(-3300 2500);
WIRE 16 -1 (-3725 2450)(-3300 2450);
WIRE 16 -1 (-3725 2400)(-3300 2400);
WIRE 16 -1 (-3725 3750)(-3300 3750);
WIRE 16 -1 (-3725 3800)(-3300 3800);
WIRE 16 -1 (-3725 3850)(-3300 3850);
WIRE 16 -1 (-3725 3950)(-3300 3950);
WIRE 16 -1 (-3725 3900)(-3300 3900);
WIRE 16 -1 (-3725 4050)(-3300 4050);
WIRE 16 -1 (-3725 4000)(-3300 4000);
WIRE 16 -1 (-3725 3650)(-3300 3650);
WIRE 16 -1 (-3725 3600)(-3300 3600);
WIRE 16 -1 (-3725 3550)(-3300 3550);
WIRE 16 -1 (-3725 3500)(-3300 3500);
WIRE 16 -1 (-3725 3450)(-3300 3450);
WIRE 16 -1 (-3725 3400)(-3300 3400);
WIRE 16 -1 (-3725 3350)(-3300 3350);
WIRE 16 -1 (-3725 3300)(-3300 3300);
WIRE 16 -1 (-3725 3200)(-3300 3200);
WIRE 16 -1 (-3725 3150)(-3300 3150);
WIRE 16 -1 (-3725 3100)(-3300 3100);
WIRE 16 -1 (-3725 4200)(-3300 4200);
WIRE 16 -1 (-3725 4100)(-3300 4100);
WIRE 16 -1 (-3725 4700)(-3300 4700);
WIRE 16 -1 (-3725 5100)(-3300 5100);
WIRE 16 -1 (-3300 5000)(-3725 5000);
WIRE 16 -1 (-3725 4950)(-3300 4950);
WIRE 16 -1 (-3725 4900)(-3300 4900);
WIRE 16 -1 (-3725 4850)(-3300 4850);
WIRE 16 -1 (-3725 4800)(-3300 4800);
WIRE 16 -1 (-3725 4750)(-3300 4750);
WIRE 16 -1 (-3725 4650)(-3300 4650);
WIRE 16 -1 (-3725 4550)(-3300 4550);
WIRE 16 -1 (-3725 4500)(-3300 4500);
WIRE 16 -1 (-3725 4450)(-3300 4450);
WIRE 16 -1 (-3725 4400)(-3300 4400);
WIRE 16 -1 (-3725 4350)(-3300 4350);
WIRE 16 -1 (-3725 4300)(-3300 4300);
WIRE 16 -1 (-3725 4250)(-3300 4250);
WIRE 16 -1 (-3725 5900)(-3300 5900);
WIRE 16 -1 (-3725 5850)(-3300 5850);
WIRE 16 -1 (-3725 5800)(-3300 5800);
WIRE 16 -1 (-3725 5750)(-3300 5750);
WIRE 16 -1 (-3725 5700)(-3300 5700);
WIRE 16 -1 (-3725 5650)(-3300 5650);
WIRE 16 -1 (-3725 5600)(-3300 5600);
WIRE 16 -1 (-3725 5550)(-3300 5550);
WIRE 16 -1 (-3725 5450)(-3300 5450);
WIRE 16 -1 (-3725 5400)(-3300 5400);
WIRE 16 -1 (-3725 5350)(-3300 5350);
WIRE 16 -1 (-3725 5300)(-3300 5300);
WIRE 16 -1 (-3725 5250)(-3300 5250);
WIRE 16 -1 (-3725 5200)(-3300 5200);
WIRE 16 -1 (-3725 5150)(-3300 5150);
QUIT
